FILE_TYPE = MACRO_DRAWING;
SET COLOR_WIRE YELLOW;
SET COLOR_PROP ORANGE;
SET COLOR_DOT WHITE;
SET COLOR_ARC YELLOW;
SET COLOR_BODY GREEN;
SET COLOR_NOTE PURPLE;
SET PROP_DISPLAY VALUE;
SET PAGE_NUMBER P42;
FORCEADD UNIVERSAL_GND..1
(-3275 -850);
FORCEPROP 3 LASTPIN (-3275 -800) SIG_NAME GND\g
J 0
(-3265 -790);
DISPLAY 0.659574 (-3265 -790);
PAINT MONO (-3265 -790);
DISPLAY INVISIBLE (-3265 -790);
FORCEPROP 2 LAST CDS_LIB logical_power
J 0
(-3275 -850);
PAINT MONO (-3275 -850);
DISPLAY INVISIBLE (-3275 -850);
FORCEPROP 1 LAST HDL_POWER GND
J 1
(-3250 -925);
DISPLAY 0.872340 (-3250 -925);
PAINT GREEN (-3250 -925);
DISPLAY INVISIBLE (-3250 -925);
FORCEPROP 1 LAST PATH I1
J 0
(-3200 -850);
DISPLAY 0.872340 (-3200 -850);
PAINT AQUA (-3200 -850);
DISPLAY INVISIBLE (-3200 -850);
FORCEADD SOCKET4677_AZIF0045P001C01CS..40
(-1825 1675);
FORCEPROP 1 LAST PART_NUMBER DGA^7000023
J 0
(-2875 3925);
DISPLAY 0.723404 (-2875 3925);
PAINT GREEN (-2875 3925);
DISPLAY INVISIBLE (-2875 3925);
FORCEPROP 2 LAST PART_TYPE SMLF
J 0
(-2875 4100);
DISPLAY 1.021277 (-2875 4100);
FORCEPROP 1 LAST MATERIAL IO
J 0
(-2875 3850);
DISPLAY 0.723404 (-2875 3850);
PAINT GREEN (-2875 3850);
FORCEPROP 2 LAST VALUE SOCKET4677_AZIF0045-P001C01CS
J 0
(-2875 4050);
DISPLAY 1.021277 (-2875 4050);
FORCEPROP 1 LAST $LOCATION U2
J 0
(-2875 4000);
DISPLAY 0.723404 (-2875 4000);
PAINT GREEN (-2875 4000);
FORCEPROP 0 LASTPIN (-3025 2650) $PN AA19
J 2
(-3035 2660);
DISPLAY 0.680851 (-3035 2660);
PAINT MONO (-3035 2660);
FORCEPROP 0 LASTPIN (-3025 2700) $PN AA23
J 2
(-3035 2710);
DISPLAY 0.680851 (-3035 2710);
PAINT MONO (-3035 2710);
FORCEPROP 0 LASTPIN (-3025 2750) $PN AA25
J 2
(-3035 2760);
DISPLAY 0.680851 (-3035 2760);
PAINT MONO (-3035 2760);
FORCEPROP 0 LASTPIN (-3025 2800) $PN AA29
J 2
(-3035 2810);
DISPLAY 0.680851 (-3035 2810);
PAINT MONO (-3035 2810);
FORCEPROP 0 LASTPIN (-3025 2850) $PN AA31
J 2
(-3035 2860);
DISPLAY 0.680851 (-3035 2860);
PAINT MONO (-3035 2860);
FORCEPROP 0 LASTPIN (-3025 2900) $PN AA35
J 2
(-3035 2910);
DISPLAY 0.680851 (-3035 2910);
PAINT MONO (-3035 2910);
FORCEPROP 0 LASTPIN (-3025 2950) $PN AA37
J 2
(-3035 2960);
DISPLAY 0.680851 (-3035 2960);
PAINT MONO (-3035 2960);
FORCEPROP 0 LASTPIN (-3025 3000) $PN AA41
J 2
(-3035 3010);
DISPLAY 0.680851 (-3035 3010);
PAINT MONO (-3035 3010);
FORCEPROP 0 LASTPIN (-3025 3050) $PN AA43
J 2
(-3035 3060);
DISPLAY 0.680851 (-3035 3060);
PAINT MONO (-3035 3060);
FORCEPROP 0 LASTPIN (-3025 3100) $PN AA48
J 2
(-3035 3110);
DISPLAY 0.680851 (-3035 3110);
PAINT MONO (-3035 3110);
FORCEPROP 0 LASTPIN (-3025 3150) $PN AA50
J 2
(-3035 3160);
DISPLAY 0.680851 (-3035 3160);
PAINT MONO (-3035 3160);
FORCEPROP 0 LASTPIN (-3025 3200) $PN AA54
J 2
(-3035 3210);
DISPLAY 0.680851 (-3035 3210);
PAINT MONO (-3035 3210);
FORCEPROP 0 LASTPIN (-3025 3250) $PN AA56
J 2
(-3035 3260);
DISPLAY 0.680851 (-3035 3260);
PAINT MONO (-3035 3260);
FORCEPROP 0 LASTPIN (-3025 3300) $PN AA60
J 2
(-3035 3310);
DISPLAY 0.680851 (-3035 3310);
PAINT MONO (-3035 3310);
FORCEPROP 0 LASTPIN (-3025 3350) $PN AA62
J 2
(-3035 3360);
DISPLAY 0.680851 (-3035 3360);
PAINT MONO (-3035 3360);
FORCEPROP 0 LASTPIN (-3025 3400) $PN AA66
J 2
(-3035 3410);
DISPLAY 0.680851 (-3035 3410);
PAINT MONO (-3035 3410);
FORCEPROP 0 LASTPIN (-3025 3450) $PN AA68
J 2
(-3035 3460);
DISPLAY 0.680851 (-3035 3460);
PAINT MONO (-3035 3460);
FORCEPROP 0 LASTPIN (-3025 3500) $PN AA72
J 2
(-3035 3510);
DISPLAY 0.680851 (-3035 3510);
PAINT MONO (-3035 3510);
FORCEPROP 0 LASTPIN (-3025 3550) $PN AA74
J 2
(-3035 3560);
DISPLAY 0.680851 (-3035 3560);
PAINT MONO (-3035 3560);
FORCEPROP 0 LASTPIN (-3025 3600) $PN AA78
J 2
(-3035 3610);
DISPLAY 0.680851 (-3035 3610);
PAINT MONO (-3035 3610);
FORCEPROP 0 LASTPIN (-3025 3650) $PN AA80
J 2
(-3035 3660);
DISPLAY 0.680851 (-3035 3660);
PAINT MONO (-3035 3660);
FORCEPROP 0 LASTPIN (-625 400) $PN P32
J 0
(-615 410);
DISPLAY 0.680851 (-615 410);
PAINT MONO (-615 410);
FORCEPROP 0 LASTPIN (-625 -300) $PN N76
J 0
(-615 -290);
DISPLAY 0.680851 (-615 -290);
PAINT MONO (-615 -290);
FORCEPROP 0 LASTPIN (-625 700) $PN P51
J 0
(-615 710);
DISPLAY 0.680851 (-615 710);
PAINT MONO (-615 710);
FORCEPROP 0 LASTPIN (-625 -250) $PN N78
J 0
(-615 -240);
DISPLAY 0.680851 (-615 -240);
PAINT MONO (-615 -240);
FORCEPROP 0 LASTPIN (-625 800) $PN P57
J 0
(-615 810);
DISPLAY 0.680851 (-615 810);
PAINT MONO (-615 810);
FORCEPROP 0 LASTPIN (-625 -200) $PN N80
J 0
(-615 -190);
DISPLAY 0.680851 (-615 -190);
PAINT MONO (-615 -190);
FORCEPROP 0 LASTPIN (-625 -150) $PN N82
J 0
(-615 -140);
DISPLAY 0.680851 (-615 -140);
PAINT MONO (-615 -140);
FORCEPROP 0 LASTPIN (-625 -100) $PN N84
J 0
(-615 -90);
DISPLAY 0.680851 (-615 -90);
PAINT MONO (-615 -90);
FORCEPROP 0 LASTPIN (-625 -50) $PN N88
J 0
(-615 -40);
DISPLAY 0.680851 (-615 -40);
PAINT MONO (-615 -40);
FORCEPROP 0 LASTPIN (-625 1050) $PN P71
J 0
(-615 1060);
DISPLAY 0.680851 (-615 1060);
PAINT MONO (-615 1060);
FORCEPROP 0 LASTPIN (-625 100) $PN P12
J 0
(-615 110);
DISPLAY 0.680851 (-615 110);
PAINT MONO (-615 110);
FORCEPROP 0 LASTPIN (-625 150) $PN P16
J 0
(-615 160);
DISPLAY 0.680851 (-615 160);
PAINT MONO (-615 160);
FORCEPROP 0 LASTPIN (-625 200) $PN P20
J 0
(-615 210);
DISPLAY 0.680851 (-615 210);
PAINT MONO (-615 210);
FORCEPROP 0 LASTPIN (-625 250) $PN P22
J 0
(-615 260);
DISPLAY 0.680851 (-615 260);
PAINT MONO (-615 260);
FORCEPROP 0 LASTPIN (-625 300) $PN P26
J 0
(-615 310);
DISPLAY 0.680851 (-615 310);
PAINT MONO (-615 310);
FORCEPROP 0 LASTPIN (-625 350) $PN P28
J 0
(-615 360);
DISPLAY 0.680851 (-615 360);
PAINT MONO (-615 360);
FORCEPROP 0 LASTPIN (-625 1300) $PN R1
J 0
(-615 1310);
DISPLAY 0.680851 (-615 1310);
PAINT MONO (-615 1310);
FORCEPROP 0 LASTPIN (-625 450) $PN P34
J 0
(-615 460);
DISPLAY 0.680851 (-615 460);
PAINT MONO (-615 460);
FORCEPROP 0 LASTPIN (-625 500) $PN P38
J 0
(-615 510);
DISPLAY 0.680851 (-615 510);
PAINT MONO (-615 510);
FORCEPROP 0 LASTPIN (-625 1550) $PN R19
J 0
(-615 1560);
DISPLAY 0.680851 (-615 1560);
PAINT MONO (-615 1560);
FORCEPROP 0 LASTPIN (-625 1600) $PN R23
J 0
(-615 1610);
DISPLAY 0.680851 (-615 1610);
PAINT MONO (-615 1610);
FORCEPROP 0 LASTPIN (-625 0) $PN P4
J 0
(-615 10);
DISPLAY 0.680851 (-615 10);
PAINT MONO (-615 10);
FORCEPROP 0 LASTPIN (-625 550) $PN P40
J 0
(-615 560);
DISPLAY 0.680851 (-615 560);
PAINT MONO (-615 560);
FORCEPROP 0 LASTPIN (-625 600) $PN P44
J 0
(-615 610);
DISPLAY 0.680851 (-615 610);
PAINT MONO (-615 610);
FORCEPROP 0 LASTPIN (-625 650) $PN P47
J 0
(-615 660);
DISPLAY 0.680851 (-615 660);
PAINT MONO (-615 660);
FORCEPROP 0 LASTPIN (-625 750) $PN P53
J 0
(-615 760);
DISPLAY 0.680851 (-615 760);
PAINT MONO (-615 760);
FORCEPROP 0 LASTPIN (-625 850) $PN P59
J 0
(-615 860);
DISPLAY 0.680851 (-615 860);
PAINT MONO (-615 860);
FORCEPROP 0 LASTPIN (-625 900) $PN P63
J 0
(-615 910);
DISPLAY 0.680851 (-615 910);
PAINT MONO (-615 910);
FORCEPROP 0 LASTPIN (-625 2000) $PN R48
J 0
(-615 2010);
DISPLAY 0.680851 (-615 2010);
PAINT MONO (-615 2010);
FORCEPROP 0 LASTPIN (-625 950) $PN P65
J 0
(-615 960);
DISPLAY 0.680851 (-615 960);
PAINT MONO (-615 960);
FORCEPROP 0 LASTPIN (-625 1000) $PN P69
J 0
(-615 1010);
DISPLAY 0.680851 (-615 1010);
PAINT MONO (-615 1010);
FORCEPROP 0 LASTPIN (-625 1100) $PN P75
J 0
(-615 1110);
DISPLAY 0.680851 (-615 1110);
PAINT MONO (-615 1110);
FORCEPROP 0 LASTPIN (-625 1150) $PN P77
J 0
(-615 1160);
DISPLAY 0.680851 (-615 1160);
PAINT MONO (-615 1160);
FORCEPROP 0 LASTPIN (-625 2200) $PN R60
J 0
(-615 2210);
DISPLAY 0.680851 (-615 2210);
PAINT MONO (-615 2210);
FORCEPROP 0 LASTPIN (-625 50) $PN P8
J 0
(-615 60);
DISPLAY 0.680851 (-615 60);
PAINT MONO (-615 60);
FORCEPROP 0 LASTPIN (-625 2300) $PN R66
J 0
(-615 2310);
DISPLAY 0.680851 (-615 2310);
PAINT MONO (-615 2310);
FORCEPROP 0 LASTPIN (-625 1200) $PN P87
J 0
(-615 1210);
DISPLAY 0.680851 (-615 1210);
PAINT MONO (-615 1210);
FORCEPROP 0 LASTPIN (-625 1250) $PN P91
J 0
(-615 1260);
DISPLAY 0.680851 (-615 1260);
PAINT MONO (-615 1260);
FORCEPROP 0 LASTPIN (-625 1450) $PN R13
J 0
(-615 1460);
DISPLAY 0.680851 (-615 1460);
PAINT MONO (-615 1460);
FORCEPROP 0 LASTPIN (-625 1500) $PN R17
J 0
(-615 1510);
DISPLAY 0.680851 (-615 1510);
PAINT MONO (-615 1510);
FORCEPROP 0 LASTPIN (-625 1650) $PN R25
J 0
(-615 1660);
DISPLAY 0.680851 (-615 1660);
PAINT MONO (-615 1660);
FORCEPROP 0 LASTPIN (-625 1700) $PN R29
J 0
(-615 1710);
DISPLAY 0.680851 (-615 1710);
PAINT MONO (-615 1710);
FORCEPROP 0 LASTPIN (-625 1750) $PN R31
J 0
(-615 1760);
DISPLAY 0.680851 (-615 1760);
PAINT MONO (-615 1760);
FORCEPROP 0 LASTPIN (-625 1800) $PN R35
J 0
(-615 1810);
DISPLAY 0.680851 (-615 1810);
PAINT MONO (-615 1810);
FORCEPROP 0 LASTPIN (-625 2750) $PN T12
J 0
(-615 2760);
DISPLAY 0.680851 (-615 2760);
PAINT MONO (-615 2760);
FORCEPROP 0 LASTPIN (-625 2800) $PN T16
J 0
(-615 2810);
DISPLAY 0.680851 (-615 2810);
PAINT MONO (-615 2810);
FORCEPROP 0 LASTPIN (-625 2850) $PN T18
J 0
(-615 2860);
DISPLAY 0.680851 (-615 2860);
PAINT MONO (-615 2860);
FORCEPROP 0 LASTPIN (-625 1850) $PN R37
J 0
(-615 1860);
DISPLAY 0.680851 (-615 1860);
PAINT MONO (-615 1860);
FORCEPROP 0 LASTPIN (-625 1900) $PN R41
J 0
(-615 1910);
DISPLAY 0.680851 (-615 1910);
PAINT MONO (-615 1910);
FORCEPROP 0 LASTPIN (-625 1950) $PN R43
J 0
(-615 1960);
DISPLAY 0.680851 (-615 1960);
PAINT MONO (-615 1960);
FORCEPROP 0 LASTPIN (-625 1350) $PN R5
J 0
(-615 1360);
DISPLAY 0.680851 (-615 1360);
PAINT MONO (-615 1360);
FORCEPROP 0 LASTPIN (-625 3000) $PN T36
J 0
(-615 3010);
DISPLAY 0.680851 (-615 3010);
PAINT MONO (-615 3010);
FORCEPROP 0 LASTPIN (-625 2050) $PN R50
J 0
(-615 2060);
DISPLAY 0.680851 (-615 2060);
PAINT MONO (-615 2060);
FORCEPROP 0 LASTPIN (-625 2100) $PN R54
J 0
(-615 2110);
DISPLAY 0.680851 (-615 2110);
PAINT MONO (-615 2110);
FORCEPROP 0 LASTPIN (-625 3100) $PN T49
J 0
(-615 3110);
DISPLAY 0.680851 (-615 3110);
PAINT MONO (-615 3110);
FORCEPROP 0 LASTPIN (-625 3150) $PN T55
J 0
(-615 3160);
DISPLAY 0.680851 (-615 3160);
PAINT MONO (-615 3160);
FORCEPROP 0 LASTPIN (-625 2150) $PN R56
J 0
(-615 2160);
DISPLAY 0.680851 (-615 2160);
PAINT MONO (-615 2160);
FORCEPROP 0 LASTPIN (-625 2250) $PN R62
J 0
(-615 2260);
DISPLAY 0.680851 (-615 2260);
PAINT MONO (-615 2260);
FORCEPROP 0 LASTPIN (-625 2350) $PN R68
J 0
(-615 2360);
DISPLAY 0.680851 (-615 2360);
PAINT MONO (-615 2360);
FORCEPROP 0 LASTPIN (-625 2400) $PN R72
J 0
(-615 2410);
DISPLAY 0.680851 (-615 2410);
PAINT MONO (-615 2410);
FORCEPROP 0 LASTPIN (-625 2450) $PN R74
J 0
(-615 2460);
DISPLAY 0.680851 (-615 2460);
PAINT MONO (-615 2460);
FORCEPROP 0 LASTPIN (-625 2500) $PN R78
J 0
(-615 2510);
DISPLAY 0.680851 (-615 2510);
PAINT MONO (-615 2510);
FORCEPROP 0 LASTPIN (-625 2550) $PN R84
J 0
(-615 2560);
DISPLAY 0.680851 (-615 2560);
PAINT MONO (-615 2560);
FORCEPROP 0 LASTPIN (-625 2600) $PN R88
J 0
(-615 2610);
DISPLAY 0.680851 (-615 2610);
PAINT MONO (-615 2610);
FORCEPROP 0 LASTPIN (-625 1400) $PN R9
J 0
(-615 1410);
DISPLAY 0.680851 (-615 1410);
PAINT MONO (-615 1410);
FORCEPROP 0 LASTPIN (-625 2900) $PN T24
J 0
(-615 2910);
DISPLAY 0.680851 (-615 2910);
PAINT MONO (-615 2910);
FORCEPROP 0 LASTPIN (-625 2950) $PN T30
J 0
(-615 2960);
DISPLAY 0.680851 (-615 2960);
PAINT MONO (-615 2960);
FORCEPROP 0 LASTPIN (-625 2650) $PN T4
J 0
(-615 2660);
DISPLAY 0.680851 (-615 2660);
PAINT MONO (-615 2660);
FORCEPROP 0 LASTPIN (-625 3050) $PN T42
J 0
(-615 3060);
DISPLAY 0.680851 (-615 3060);
PAINT MONO (-615 3060);
FORCEPROP 0 LASTPIN (-625 3200) $PN T61
J 0
(-615 3210);
DISPLAY 0.680851 (-615 3210);
PAINT MONO (-615 3210);
FORCEPROP 0 LASTPIN (-625 3250) $PN T67
J 0
(-615 3260);
DISPLAY 0.680851 (-615 3260);
PAINT MONO (-615 3260);
FORCEPROP 0 LASTPIN (-625 3500) $PN U52
J 0
(-615 3510);
DISPLAY 0.680851 (-615 3510);
PAINT MONO (-615 3510);
FORCEPROP 0 LASTPIN (-625 3300) $PN T73
J 0
(-615 3310);
DISPLAY 0.680851 (-615 3310);
PAINT MONO (-615 3310);
FORCEPROP 0 LASTPIN (-625 3350) $PN T79
J 0
(-615 3360);
DISPLAY 0.680851 (-615 3360);
PAINT MONO (-615 3360);
FORCEPROP 0 LASTPIN (-625 2700) $PN T8
J 0
(-615 2710);
DISPLAY 0.680851 (-615 2710);
PAINT MONO (-615 2710);
FORCEPROP 0 LASTPIN (-625 3400) $PN T83
J 0
(-615 3410);
DISPLAY 0.680851 (-615 3410);
PAINT MONO (-615 3410);
FORCEPROP 0 LASTPIN (-625 3450) $PN U39
J 0
(-615 3460);
DISPLAY 0.680851 (-615 3460);
PAINT MONO (-615 3460);
FORCEPROP 0 LASTPIN (-625 3550) $PN U82
J 0
(-615 3560);
DISPLAY 0.680851 (-615 3560);
PAINT MONO (-615 3560);
FORCEPROP 0 LASTPIN (-625 3600) $PN U84
J 0
(-615 3610);
DISPLAY 0.680851 (-615 3610);
PAINT MONO (-615 3610);
FORCEPROP 0 LASTPIN (-625 3650) $PN U88
J 0
(-615 3660);
DISPLAY 0.680851 (-615 3660);
PAINT MONO (-615 3660);
FORCEPROP 0 LASTPIN (-3025 -200) $PN V12
J 2
(-3035 -190);
DISPLAY 0.680851 (-3035 -190);
PAINT MONO (-3035 -190);
FORCEPROP 0 LASTPIN (-3025 -150) $PN V16
J 2
(-3035 -140);
DISPLAY 0.680851 (-3035 -140);
PAINT MONO (-3035 -140);
FORCEPROP 0 LASTPIN (-3025 -100) $PN V18
J 2
(-3035 -90);
DISPLAY 0.680851 (-3035 -90);
PAINT MONO (-3035 -90);
FORCEPROP 0 LASTPIN (-3025 -50) $PN V20
J 2
(-3035 -40);
DISPLAY 0.680851 (-3035 -40);
PAINT MONO (-3035 -40);
FORCEPROP 0 LASTPIN (-3025 0) $PN V22
J 2
(-3035 10);
DISPLAY 0.680851 (-3035 10);
PAINT MONO (-3035 10);
FORCEPROP 0 LASTPIN (-3025 50) $PN V24
J 2
(-3035 60);
DISPLAY 0.680851 (-3035 60);
PAINT MONO (-3035 60);
FORCEPROP 0 LASTPIN (-3025 100) $PN V26
J 2
(-3035 110);
DISPLAY 0.680851 (-3035 110);
PAINT MONO (-3035 110);
FORCEPROP 0 LASTPIN (-3025 150) $PN V28
J 2
(-3035 160);
DISPLAY 0.680851 (-3035 160);
PAINT MONO (-3035 160);
FORCEPROP 0 LASTPIN (-3025 200) $PN V30
J 2
(-3035 210);
DISPLAY 0.680851 (-3035 210);
PAINT MONO (-3035 210);
FORCEPROP 0 LASTPIN (-3025 250) $PN V32
J 2
(-3035 260);
DISPLAY 0.680851 (-3035 260);
PAINT MONO (-3035 260);
FORCEPROP 0 LASTPIN (-3025 300) $PN V34
J 2
(-3035 310);
DISPLAY 0.680851 (-3035 310);
PAINT MONO (-3035 310);
FORCEPROP 0 LASTPIN (-3025 350) $PN V36
J 2
(-3035 360);
DISPLAY 0.680851 (-3035 360);
PAINT MONO (-3035 360);
FORCEPROP 0 LASTPIN (-3025 400) $PN V38
J 2
(-3035 410);
DISPLAY 0.680851 (-3035 410);
PAINT MONO (-3035 410);
FORCEPROP 0 LASTPIN (-3025 -300) $PN V4
J 2
(-3035 -290);
DISPLAY 0.680851 (-3035 -290);
PAINT MONO (-3035 -290);
FORCEPROP 0 LASTPIN (-3025 650) $PN V49
J 2
(-3035 660);
DISPLAY 0.680851 (-3035 660);
PAINT MONO (-3035 660);
FORCEPROP 0 LASTPIN (-3025 450) $PN V40
J 2
(-3035 460);
DISPLAY 0.680851 (-3035 460);
PAINT MONO (-3035 460);
FORCEPROP 0 LASTPIN (-3025 500) $PN V42
J 2
(-3035 510);
DISPLAY 0.680851 (-3035 510);
PAINT MONO (-3035 510);
FORCEPROP 0 LASTPIN (-3025 550) $PN V44
J 2
(-3035 560);
DISPLAY 0.680851 (-3035 560);
PAINT MONO (-3035 560);
FORCEPROP 0 LASTPIN (-3025 600) $PN V47
J 2
(-3035 610);
DISPLAY 0.680851 (-3035 610);
PAINT MONO (-3035 610);
FORCEPROP 0 LASTPIN (-3025 700) $PN V51
J 2
(-3035 710);
DISPLAY 0.680851 (-3035 710);
PAINT MONO (-3035 710);
FORCEPROP 0 LASTPIN (-3025 750) $PN V53
J 2
(-3035 760);
DISPLAY 0.680851 (-3035 760);
PAINT MONO (-3035 760);
FORCEPROP 0 LASTPIN (-3025 800) $PN V55
J 2
(-3035 810);
DISPLAY 0.680851 (-3035 810);
PAINT MONO (-3035 810);
FORCEPROP 0 LASTPIN (-3025 850) $PN V57
J 2
(-3035 860);
DISPLAY 0.680851 (-3035 860);
PAINT MONO (-3035 860);
FORCEPROP 0 LASTPIN (-3025 900) $PN V59
J 2
(-3035 910);
DISPLAY 0.680851 (-3035 910);
PAINT MONO (-3035 910);
FORCEPROP 0 LASTPIN (-3025 950) $PN V61
J 2
(-3035 960);
DISPLAY 0.680851 (-3035 960);
PAINT MONO (-3035 960);
FORCEPROP 0 LASTPIN (-3025 1200) $PN V71
J 2
(-3035 1210);
DISPLAY 0.680851 (-3035 1210);
PAINT MONO (-3035 1210);
FORCEPROP 0 LASTPIN (-3025 1250) $PN V73
J 2
(-3035 1260);
DISPLAY 0.680851 (-3035 1260);
PAINT MONO (-3035 1260);
FORCEPROP 0 LASTPIN (-3025 1000) $PN V63
J 2
(-3035 1010);
DISPLAY 0.680851 (-3035 1010);
PAINT MONO (-3035 1010);
FORCEPROP 0 LASTPIN (-3025 1050) $PN V65
J 2
(-3035 1060);
DISPLAY 0.680851 (-3035 1060);
PAINT MONO (-3035 1060);
FORCEPROP 0 LASTPIN (-3025 1100) $PN V67
J 2
(-3035 1110);
DISPLAY 0.680851 (-3035 1110);
PAINT MONO (-3035 1110);
FORCEPROP 0 LASTPIN (-3025 1150) $PN V69
J 2
(-3035 1160);
DISPLAY 0.680851 (-3035 1160);
PAINT MONO (-3035 1160);
FORCEPROP 0 LASTPIN (-3025 1300) $PN V75
J 2
(-3035 1310);
DISPLAY 0.680851 (-3035 1310);
PAINT MONO (-3035 1310);
FORCEPROP 0 LASTPIN (-3025 1500) $PN V91
J 2
(-3035 1510);
DISPLAY 0.680851 (-3035 1510);
PAINT MONO (-3035 1510);
FORCEPROP 0 LASTPIN (-3025 1550) $PN W1
J 2
(-3035 1560);
DISPLAY 0.680851 (-3035 1560);
PAINT MONO (-3035 1560);
FORCEPROP 0 LASTPIN (-3025 1700) $PN W13
J 2
(-3035 1710);
DISPLAY 0.680851 (-3035 1710);
PAINT MONO (-3035 1710);
FORCEPROP 0 LASTPIN (-3025 1350) $PN V77
J 2
(-3035 1360);
DISPLAY 0.680851 (-3035 1360);
PAINT MONO (-3035 1360);
FORCEPROP 0 LASTPIN (-3025 1400) $PN V79
J 2
(-3035 1410);
DISPLAY 0.680851 (-3035 1410);
PAINT MONO (-3035 1410);
FORCEPROP 0 LASTPIN (-3025 -250) $PN V8
J 2
(-3035 -240);
DISPLAY 0.680851 (-3035 -240);
PAINT MONO (-3035 -240);
FORCEPROP 0 LASTPIN (-3025 1450) $PN V87
J 2
(-3035 1460);
DISPLAY 0.680851 (-3035 1460);
PAINT MONO (-3035 1460);
FORCEPROP 0 LASTPIN (-3025 1600) $PN W5
J 2
(-3035 1610);
DISPLAY 0.680851 (-3035 1610);
PAINT MONO (-3035 1610);
FORCEPROP 0 LASTPIN (-3025 1800) $PN W52
J 2
(-3035 1810);
DISPLAY 0.680851 (-3035 1810);
PAINT MONO (-3035 1810);
FORCEPROP 0 LASTPIN (-3025 1750) $PN W39
J 2
(-3035 1760);
DISPLAY 0.680851 (-3035 1760);
PAINT MONO (-3035 1760);
FORCEPROP 0 LASTPIN (-3025 1850) $PN W84
J 2
(-3035 1860);
DISPLAY 0.680851 (-3035 1860);
PAINT MONO (-3035 1860);
FORCEPROP 0 LASTPIN (-3025 1900) $PN W88
J 2
(-3035 1910);
DISPLAY 0.680851 (-3035 1910);
PAINT MONO (-3035 1910);
FORCEPROP 0 LASTPIN (-3025 1650) $PN W9
J 2
(-3035 1660);
DISPLAY 0.680851 (-3035 1660);
PAINT MONO (-3035 1660);
FORCEPROP 0 LASTPIN (-3025 2050) $PN Y12
J 2
(-3035 2060);
DISPLAY 0.680851 (-3035 2060);
PAINT MONO (-3035 2060);
FORCEPROP 0 LASTPIN (-3025 2100) $PN Y16
J 2
(-3035 2110);
DISPLAY 0.680851 (-3035 2110);
PAINT MONO (-3035 2110);
FORCEPROP 0 LASTPIN (-3025 2150) $PN Y18
J 2
(-3035 2160);
DISPLAY 0.680851 (-3035 2160);
PAINT MONO (-3035 2160);
FORCEPROP 0 LASTPIN (-3025 2200) $PN Y24
J 2
(-3035 2210);
DISPLAY 0.680851 (-3035 2210);
PAINT MONO (-3035 2210);
FORCEPROP 0 LASTPIN (-3025 2250) $PN Y30
J 2
(-3035 2260);
DISPLAY 0.680851 (-3035 2260);
PAINT MONO (-3035 2260);
FORCEPROP 0 LASTPIN (-3025 2300) $PN Y36
J 2
(-3035 2310);
DISPLAY 0.680851 (-3035 2310);
PAINT MONO (-3035 2310);
FORCEPROP 0 LASTPIN (-3025 1950) $PN Y4
J 2
(-3035 1960);
DISPLAY 0.680851 (-3035 1960);
PAINT MONO (-3035 1960);
FORCEPROP 0 LASTPIN (-3025 2350) $PN Y42
J 2
(-3035 2360);
DISPLAY 0.680851 (-3035 2360);
PAINT MONO (-3035 2360);
FORCEPROP 0 LASTPIN (-3025 2500) $PN Y61
J 2
(-3035 2510);
DISPLAY 0.680851 (-3035 2510);
PAINT MONO (-3035 2510);
FORCEPROP 0 LASTPIN (-3025 2550) $PN Y67
J 2
(-3035 2560);
DISPLAY 0.680851 (-3035 2560);
PAINT MONO (-3035 2560);
FORCEPROP 0 LASTPIN (-3025 2400) $PN Y49
J 2
(-3035 2410);
DISPLAY 0.680851 (-3035 2410);
PAINT MONO (-3035 2410);
FORCEPROP 0 LASTPIN (-3025 2450) $PN Y55
J 2
(-3035 2460);
DISPLAY 0.680851 (-3035 2460);
PAINT MONO (-3035 2460);
FORCEPROP 0 LASTPIN (-3025 2000) $PN Y8
J 2
(-3035 2010);
DISPLAY 0.680851 (-3035 2010);
PAINT MONO (-3035 2010);
FORCEPROP 0 LASTPIN (-3025 2600) $PN Y73
J 2
(-3035 2610);
DISPLAY 0.680851 (-3035 2610);
PAINT MONO (-3035 2610);
FORCEPROP 2 LAST CDS_LIB pure_quanta
J 0
(-1825 1675);
DISPLAY INVISIBLE (-1825 1675);
FORCEPROP 1 LAST NEEDS_NO_SIZE TRUE
J 0
(-1825 1675);
DISPLAY 0.723404 (-1825 1675);
PAINT GREEN (-1825 1675);
DISPLAY INVISIBLE (-1825 1675);
FORCEPROP 1 LAST CDS_LMAN_SYM_OUTLINE -1050,2150,1050,-2100
J 0
(-1825 1675);
DISPLAY 0.468085 (-1825 1675);
PAINT GREEN (-1825 1675);
DISPLAY INVISIBLE (-1825 1675);
FORCEPROP 2 LAST CDS_LOCATION U2
J 0
(-2875 4150);
DISPLAY 1.021277 (-2875 4150);
DISPLAY INVISIBLE (-2875 4150);
FORCEPROP 0 LAST $SEC 40
J 0
(-2875 4150);
DISPLAY 0.680851 (-2875 4150);
PAINT MONO (-2875 4150);
DISPLAY INVISIBLE (-2875 4150);
FORCEPROP 2 LAST CDS_SEC 40
J 0
(-2875 4150);
DISPLAY 1.021277 (-2875 4150);
DISPLAY INVISIBLE (-2875 4150);
FORCEPROP 1 LAST PATH I10
J 0
(-1825 1675);
DISPLAY 0.723404 (-1825 1675);
PAINT GREEN (-1825 1675);
DISPLAY INVISIBLE (-1825 1675);
FORCEADD SOCKET4677_AZIF0045P001C01CS..41
(1225 1675);
FORCEPROP 1 LAST PART_NUMBER DGA^7000023
J 0
(175 3925);
DISPLAY 0.723404 (175 3925);
PAINT GREEN (175 3925);
DISPLAY INVISIBLE (175 3925);
FORCEPROP 2 LAST PART_TYPE SMLF
J 0
(175 4100);
DISPLAY 1.021277 (175 4100);
FORCEPROP 1 LAST MATERIAL IO
J 0
(175 3850);
DISPLAY 0.723404 (175 3850);
PAINT GREEN (175 3850);
FORCEPROP 2 LAST VALUE SOCKET4677_AZIF0045-P001C01CS
J 0
(175 4050);
DISPLAY 1.021277 (175 4050);
FORCEPROP 1 LAST $LOCATION U2
J 0
(175 4000);
DISPLAY 0.723404 (175 4000);
PAINT GREEN (175 4000);
FORCEPROP 0 LASTPIN (2425 -100) $PN E52
J 0
(2435 -90);
DISPLAY 0.680851 (2435 -90);
PAINT MONO (2435 -90);
FORCEPROP 0 LASTPIN (2425 -50) $PN E74
J 0
(2435 -40);
DISPLAY 0.680851 (2435 -40);
PAINT MONO (2435 -40);
FORCEPROP 0 LASTPIN (2425 50) $PN E78
J 0
(2435 60);
DISPLAY 0.680851 (2435 60);
PAINT MONO (2435 60);
FORCEPROP 0 LASTPIN (2425 0) $PN E76
J 0
(2435 10);
DISPLAY 0.680851 (2435 10);
PAINT MONO (2435 10);
FORCEPROP 0 LASTPIN (2425 100) $PN E86
J 0
(2435 110);
DISPLAY 0.680851 (2435 110);
PAINT MONO (2435 110);
FORCEPROP 0 LASTPIN (2425 250) $PN F12
J 0
(2435 260);
DISPLAY 0.680851 (2435 260);
PAINT MONO (2435 260);
FORCEPROP 0 LASTPIN (2425 300) $PN F18
J 0
(2435 310);
DISPLAY 0.680851 (2435 310);
PAINT MONO (2435 310);
FORCEPROP 0 LASTPIN (2425 500) $PN F42
J 0
(2435 510);
DISPLAY 0.680851 (2435 510);
PAINT MONO (2435 510);
FORCEPROP 0 LASTPIN (2425 600) $PN F55
J 0
(2435 610);
DISPLAY 0.680851 (2435 610);
PAINT MONO (2435 610);
FORCEPROP 0 LASTPIN (2425 200) $PN F6
J 0
(2435 210);
DISPLAY 0.680851 (2435 210);
PAINT MONO (2435 210);
FORCEPROP 0 LASTPIN (2425 650) $PN F61
J 0
(2435 660);
DISPLAY 0.680851 (2435 660);
PAINT MONO (2435 660);
FORCEPROP 0 LASTPIN (2425 700) $PN F67
J 0
(2435 710);
DISPLAY 0.680851 (2435 710);
PAINT MONO (2435 710);
FORCEPROP 0 LASTPIN (2425 750) $PN F73
J 0
(2435 760);
DISPLAY 0.680851 (2435 760);
PAINT MONO (2435 760);
FORCEPROP 0 LASTPIN (2425 800) $PN F79
J 0
(2435 810);
DISPLAY 0.680851 (2435 810);
PAINT MONO (2435 810);
FORCEPROP 0 LASTPIN (2425 1050) $PN G11
J 0
(2435 1060);
DISPLAY 0.680851 (2435 1060);
PAINT MONO (2435 1060);
FORCEPROP 0 LASTPIN (2425 1150) $PN G17
J 0
(2435 1160);
DISPLAY 0.680851 (2435 1160);
PAINT MONO (2435 1160);
FORCEPROP 0 LASTPIN (2425 1300) $PN G25
J 0
(2435 1310);
DISPLAY 0.680851 (2435 1310);
PAINT MONO (2435 1310);
FORCEPROP 0 LASTPIN (2425 950) $PN G3
J 0
(2435 960);
DISPLAY 0.680851 (2435 960);
PAINT MONO (2435 960);
FORCEPROP 0 LASTPIN (2425 1450) $PN G35
J 0
(2435 1460);
DISPLAY 0.680851 (2435 1460);
PAINT MONO (2435 1460);
FORCEPROP 0 LASTPIN (2425 1650) $PN G48
J 0
(2435 1660);
DISPLAY 0.680851 (2435 1660);
PAINT MONO (2435 1660);
FORCEPROP 0 LASTPIN (2425 1850) $PN G60
J 0
(2435 1860);
DISPLAY 0.680851 (2435 1860);
PAINT MONO (2435 1860);
FORCEPROP 0 LASTPIN (2425 1950) $PN G66
J 0
(2435 1960);
DISPLAY 0.680851 (2435 1960);
PAINT MONO (2435 1960);
FORCEPROP 0 LASTPIN (2425 2000) $PN G68
J 0
(2435 2010);
DISPLAY 0.680851 (2435 2010);
PAINT MONO (2435 2010);
FORCEPROP 0 LASTPIN (2425 1000) $PN G7
J 0
(2435 1010);
DISPLAY 0.680851 (2435 1010);
PAINT MONO (2435 1010);
FORCEPROP 0 LASTPIN (2425 2100) $PN G74
J 0
(2435 2110);
DISPLAY 0.680851 (2435 2110);
PAINT MONO (2435 2110);
FORCEPROP 0 LASTPIN (2425 2550) $PN H14
J 0
(2435 2560);
DISPLAY 0.680851 (2435 2560);
PAINT MONO (2435 2560);
FORCEPROP 0 LASTPIN (2425 2300) $PN H2
J 0
(2435 2310);
DISPLAY 0.680851 (2435 2310);
PAINT MONO (2435 2310);
FORCEPROP 0 LASTPIN (2425 3150) $PN H51
J 0
(2435 3160);
DISPLAY 0.680851 (2435 3160);
PAINT MONO (2435 3160);
FORCEPROP 0 LASTPIN (2425 3250) $PN H57
J 0
(2435 3260);
DISPLAY 0.680851 (2435 3260);
PAINT MONO (2435 3260);
FORCEPROP 0 LASTPIN (2425 3400) $PN H65
J 0
(2435 3410);
DISPLAY 0.680851 (2435 3410);
PAINT MONO (2435 3410);
FORCEPROP 0 LASTPIN (2425 3550) $PN H75
J 0
(2435 3560);
DISPLAY 0.680851 (2435 3560);
PAINT MONO (2435 3560);
FORCEPROP 0 LASTPIN (2425 350) $PN F24
J 0
(2435 360);
DISPLAY 0.680851 (2435 360);
PAINT MONO (2435 360);
FORCEPROP 0 LASTPIN (2425 400) $PN F30
J 0
(2435 410);
DISPLAY 0.680851 (2435 410);
PAINT MONO (2435 410);
FORCEPROP 0 LASTPIN (2425 450) $PN F36
J 0
(2435 460);
DISPLAY 0.680851 (2435 460);
PAINT MONO (2435 460);
FORCEPROP 0 LASTPIN (2425 150) $PN F4
J 0
(2435 160);
DISPLAY 0.680851 (2435 160);
PAINT MONO (2435 160);
FORCEPROP 0 LASTPIN (2425 550) $PN F49
J 0
(2435 560);
DISPLAY 0.680851 (2435 560);
PAINT MONO (2435 560);
FORCEPROP 0 LASTPIN (25 -150) $PN J21
J 2
(15 -140);
DISPLAY 0.680851 (15 -140);
PAINT MONO (15 -140);
FORCEPROP 0 LASTPIN (2425 850) $PN F83
J 0
(2435 860);
DISPLAY 0.680851 (2435 860);
PAINT MONO (2435 860);
FORCEPROP 0 LASTPIN (2425 900) $PN F89
J 0
(2435 910);
DISPLAY 0.680851 (2435 910);
PAINT MONO (2435 910);
FORCEPROP 0 LASTPIN (2425 1100) $PN G13
J 0
(2435 1110);
DISPLAY 0.680851 (2435 1110);
PAINT MONO (2435 1110);
FORCEPROP 0 LASTPIN (2425 1200) $PN G19
J 0
(2435 1210);
DISPLAY 0.680851 (2435 1210);
PAINT MONO (2435 1210);
FORCEPROP 0 LASTPIN (25 0) $PN J39
J 2
(15 10);
DISPLAY 0.680851 (15 10);
PAINT MONO (15 10);
FORCEPROP 0 LASTPIN (2425 1250) $PN G23
J 0
(2435 1260);
DISPLAY 0.680851 (2435 1260);
PAINT MONO (2435 1260);
FORCEPROP 0 LASTPIN (25 -300) $PN J5
J 2
(15 -290);
DISPLAY 0.680851 (15 -290);
PAINT MONO (15 -290);
FORCEPROP 0 LASTPIN (2425 1350) $PN G29
J 0
(2435 1360);
DISPLAY 0.680851 (2435 1360);
PAINT MONO (2435 1360);
FORCEPROP 0 LASTPIN (2425 1400) $PN G31
J 0
(2435 1410);
DISPLAY 0.680851 (2435 1410);
PAINT MONO (2435 1410);
FORCEPROP 0 LASTPIN (2425 1500) $PN G37
J 0
(2435 1510);
DISPLAY 0.680851 (2435 1510);
PAINT MONO (2435 1510);
FORCEPROP 0 LASTPIN (2425 1550) $PN G41
J 0
(2435 1560);
DISPLAY 0.680851 (2435 1560);
PAINT MONO (2435 1560);
FORCEPROP 0 LASTPIN (25 200) $PN J64
J 2
(15 210);
DISPLAY 0.680851 (15 210);
PAINT MONO (15 210);
FORCEPROP 0 LASTPIN (2425 1600) $PN G43
J 0
(2435 1610);
DISPLAY 0.680851 (2435 1610);
PAINT MONO (2435 1610);
FORCEPROP 0 LASTPIN (25 250) $PN J70
J 2
(15 260);
DISPLAY 0.680851 (15 260);
PAINT MONO (15 260);
FORCEPROP 0 LASTPIN (2425 1700) $PN G50
J 0
(2435 1710);
DISPLAY 0.680851 (2435 1710);
PAINT MONO (2435 1710);
FORCEPROP 0 LASTPIN (2425 1750) $PN G54
J 0
(2435 1760);
DISPLAY 0.680851 (2435 1760);
PAINT MONO (2435 1760);
FORCEPROP 0 LASTPIN (2425 1800) $PN G56
J 0
(2435 1810);
DISPLAY 0.680851 (2435 1810);
PAINT MONO (2435 1810);
FORCEPROP 0 LASTPIN (2425 1900) $PN G62
J 0
(2435 1910);
DISPLAY 0.680851 (2435 1910);
PAINT MONO (2435 1910);
FORCEPROP 0 LASTPIN (2425 2050) $PN G72
J 0
(2435 2060);
DISPLAY 0.680851 (2435 2060);
PAINT MONO (2435 2060);
FORCEPROP 0 LASTPIN (25 500) $PN J88
J 2
(15 510);
DISPLAY 0.680851 (15 510);
PAINT MONO (15 510);
FORCEPROP 0 LASTPIN (25 -250) $PN J9
J 2
(15 -240);
DISPLAY 0.680851 (15 -240);
PAINT MONO (15 -240);
FORCEPROP 0 LASTPIN (25 650) $PN K12
J 2
(15 660);
DISPLAY 0.680851 (15 660);
PAINT MONO (15 660);
FORCEPROP 0 LASTPIN (25 700) $PN K14
J 2
(15 710);
DISPLAY 0.680851 (15 710);
PAINT MONO (15 710);
FORCEPROP 0 LASTPIN (25 550) $PN K2
J 2
(15 560);
DISPLAY 0.680851 (15 560);
PAINT MONO (15 560);
FORCEPROP 0 LASTPIN (2425 2150) $PN G84
J 0
(2435 2160);
DISPLAY 0.680851 (2435 2160);
PAINT MONO (2435 2160);
FORCEPROP 0 LASTPIN (2425 2200) $PN G88
J 0
(2435 2210);
DISPLAY 0.680851 (2435 2210);
PAINT MONO (2435 2210);
FORCEPROP 0 LASTPIN (25 750) $PN K42
J 2
(15 760);
DISPLAY 0.680851 (15 760);
PAINT MONO (15 760);
FORCEPROP 0 LASTPIN (25 800) $PN K49
J 2
(15 810);
DISPLAY 0.680851 (15 810);
PAINT MONO (15 810);
FORCEPROP 0 LASTPIN (2425 2250) $PN G90
J 0
(2435 2260);
DISPLAY 0.680851 (2435 2260);
PAINT MONO (2435 2260);
FORCEPROP 0 LASTPIN (2425 2500) $PN H10
J 0
(2435 2510);
DISPLAY 0.680851 (2435 2510);
PAINT MONO (2435 2510);
FORCEPROP 0 LASTPIN (2425 2600) $PN H16
J 0
(2435 2610);
DISPLAY 0.680851 (2435 2610);
PAINT MONO (2435 2610);
FORCEPROP 0 LASTPIN (2425 2650) $PN H20
J 0
(2435 2660);
DISPLAY 0.680851 (2435 2660);
PAINT MONO (2435 2660);
FORCEPROP 0 LASTPIN (2425 2700) $PN H22
J 0
(2435 2710);
DISPLAY 0.680851 (2435 2710);
PAINT MONO (2435 2710);
FORCEPROP 0 LASTPIN (2425 2750) $PN H26
J 0
(2435 2760);
DISPLAY 0.680851 (2435 2760);
PAINT MONO (2435 2760);
FORCEPROP 0 LASTPIN (2425 2800) $PN H28
J 0
(2435 2810);
DISPLAY 0.680851 (2435 2810);
PAINT MONO (2435 2810);
FORCEPROP 0 LASTPIN (2425 2850) $PN H32
J 0
(2435 2860);
DISPLAY 0.680851 (2435 2860);
PAINT MONO (2435 2860);
FORCEPROP 0 LASTPIN (2425 2900) $PN H34
J 0
(2435 2910);
DISPLAY 0.680851 (2435 2910);
PAINT MONO (2435 2910);
FORCEPROP 0 LASTPIN (2425 2950) $PN H38
J 0
(2435 2960);
DISPLAY 0.680851 (2435 2960);
PAINT MONO (2435 2960);
FORCEPROP 0 LASTPIN (25 1250) $PN L19
J 2
(15 1260);
DISPLAY 0.680851 (15 1260);
PAINT MONO (15 1260);
FORCEPROP 0 LASTPIN (2425 2350) $PN H4
J 0
(2435 2360);
DISPLAY 0.680851 (2435 2360);
PAINT MONO (2435 2360);
FORCEPROP 0 LASTPIN (2425 3000) $PN H40
J 0
(2435 3010);
DISPLAY 0.680851 (2435 3010);
PAINT MONO (2435 3010);
FORCEPROP 0 LASTPIN (2425 3050) $PN H44
J 0
(2435 3060);
DISPLAY 0.680851 (2435 3060);
PAINT MONO (2435 3060);
FORCEPROP 0 LASTPIN (2425 3100) $PN H47
J 0
(2435 3110);
DISPLAY 0.680851 (2435 3110);
PAINT MONO (2435 3110);
FORCEPROP 0 LASTPIN (2425 3200) $PN H53
J 0
(2435 3210);
DISPLAY 0.680851 (2435 3210);
PAINT MONO (2435 3210);
FORCEPROP 0 LASTPIN (2425 3300) $PN H59
J 0
(2435 3310);
DISPLAY 0.680851 (2435 3310);
PAINT MONO (2435 3310);
FORCEPROP 0 LASTPIN (2425 2400) $PN H6
J 0
(2435 2410);
DISPLAY 0.680851 (2435 2410);
PAINT MONO (2435 2410);
FORCEPROP 0 LASTPIN (2425 3350) $PN H63
J 0
(2435 3360);
DISPLAY 0.680851 (2435 3360);
PAINT MONO (2435 3360);
FORCEPROP 0 LASTPIN (2425 3450) $PN H69
J 0
(2435 3460);
DISPLAY 0.680851 (2435 3460);
PAINT MONO (2435 3460);
FORCEPROP 0 LASTPIN (2425 3500) $PN H71
J 0
(2435 3510);
DISPLAY 0.680851 (2435 3510);
PAINT MONO (2435 3510);
FORCEPROP 0 LASTPIN (2425 3600) $PN H79
J 0
(2435 3610);
DISPLAY 0.680851 (2435 3610);
PAINT MONO (2435 3610);
FORCEPROP 0 LASTPIN (2425 2450) $PN H8
J 0
(2435 2460);
DISPLAY 0.680851 (2435 2460);
PAINT MONO (2435 2460);
FORCEPROP 0 LASTPIN (2425 3650) $PN H81
J 0
(2435 3660);
DISPLAY 0.680851 (2435 3660);
PAINT MONO (2435 3660);
FORCEPROP 0 LASTPIN (25 -200) $PN J15
J 2
(15 -190);
DISPLAY 0.680851 (15 -190);
PAINT MONO (15 -190);
FORCEPROP 0 LASTPIN (25 -100) $PN J27
J 2
(15 -90);
DISPLAY 0.680851 (15 -90);
PAINT MONO (15 -90);
FORCEPROP 0 LASTPIN (25 -50) $PN J33
J 2
(15 -40);
DISPLAY 0.680851 (15 -40);
PAINT MONO (15 -40);
FORCEPROP 0 LASTPIN (25 50) $PN J45
J 2
(15 60);
DISPLAY 0.680851 (15 60);
PAINT MONO (15 60);
FORCEPROP 0 LASTPIN (25 100) $PN J52
J 2
(15 110);
DISPLAY 0.680851 (15 110);
PAINT MONO (15 110);
FORCEPROP 0 LASTPIN (25 150) $PN J58
J 2
(15 160);
DISPLAY 0.680851 (15 160);
PAINT MONO (15 160);
FORCEPROP 0 LASTPIN (25 2200) $PN L58
J 2
(15 2210);
DISPLAY 0.680851 (15 2210);
PAINT MONO (15 2210);
FORCEPROP 0 LASTPIN (25 300) $PN J76
J 2
(15 310);
DISPLAY 0.680851 (15 310);
PAINT MONO (15 310);
FORCEPROP 0 LASTPIN (25 350) $PN J78
J 2
(15 360);
DISPLAY 0.680851 (15 360);
PAINT MONO (15 360);
FORCEPROP 0 LASTPIN (25 400) $PN J84
J 2
(15 410);
DISPLAY 0.680851 (15 410);
PAINT MONO (15 410);
FORCEPROP 0 LASTPIN (25 450) $PN J86
J 2
(15 460);
DISPLAY 0.680851 (15 460);
PAINT MONO (15 460);
FORCEPROP 0 LASTPIN (25 850) $PN K77
J 2
(15 860);
DISPLAY 0.680851 (15 860);
PAINT MONO (15 860);
FORCEPROP 0 LASTPIN (25 2500) $PN L70
J 2
(15 2510);
DISPLAY 0.680851 (15 2510);
PAINT MONO (15 2510);
FORCEPROP 0 LASTPIN (25 600) $PN K8
J 2
(15 610);
DISPLAY 0.680851 (15 610);
PAINT MONO (15 610);
FORCEPROP 0 LASTPIN (25 900) $PN K83
J 2
(15 910);
DISPLAY 0.680851 (15 910);
PAINT MONO (15 910);
FORCEPROP 0 LASTPIN (25 950) $PN K85
J 2
(15 960);
DISPLAY 0.680851 (15 960);
PAINT MONO (15 960);
FORCEPROP 0 LASTPIN (25 1100) $PN L13
J 2
(15 1110);
DISPLAY 0.680851 (15 1110);
PAINT MONO (15 1110);
FORCEPROP 0 LASTPIN (25 1150) $PN L15
J 2
(15 1160);
DISPLAY 0.680851 (15 1160);
PAINT MONO (15 1160);
FORCEPROP 0 LASTPIN (25 2750) $PN L88
J 2
(15 2760);
DISPLAY 0.680851 (15 2760);
PAINT MONO (15 2760);
FORCEPROP 0 LASTPIN (25 1050) $PN L9
J 2
(15 1060);
DISPLAY 0.680851 (15 1060);
PAINT MONO (15 1060);
FORCEPROP 0 LASTPIN (25 2800) $PN L90
J 2
(15 2810);
DISPLAY 0.680851 (15 2810);
PAINT MONO (15 2810);
FORCEPROP 0 LASTPIN (25 2950) $PN M12
J 2
(15 2960);
DISPLAY 0.680851 (15 2960);
PAINT MONO (15 2960);
FORCEPROP 0 LASTPIN (25 1200) $PN L17
J 2
(15 1210);
DISPLAY 0.680851 (15 1210);
PAINT MONO (15 1210);
FORCEPROP 0 LASTPIN (25 1300) $PN L21
J 2
(15 1310);
DISPLAY 0.680851 (15 1310);
PAINT MONO (15 1310);
FORCEPROP 0 LASTPIN (25 2850) $PN M4
J 2
(15 2860);
DISPLAY 0.680851 (15 2860);
PAINT MONO (15 2860);
FORCEPROP 0 LASTPIN (25 3000) $PN M42
J 2
(15 3010);
DISPLAY 0.680851 (15 3010);
PAINT MONO (15 3010);
FORCEPROP 0 LASTPIN (25 3050) $PN M49
J 2
(15 3060);
DISPLAY 0.680851 (15 3060);
PAINT MONO (15 3060);
FORCEPROP 0 LASTPIN (25 1350) $PN L23
J 2
(15 1360);
DISPLAY 0.680851 (15 1360);
PAINT MONO (15 1360);
FORCEPROP 0 LASTPIN (25 1400) $PN L25
J 2
(15 1410);
DISPLAY 0.680851 (15 1410);
PAINT MONO (15 1410);
FORCEPROP 0 LASTPIN (25 2900) $PN M8
J 2
(15 2910);
DISPLAY 0.680851 (15 2910);
PAINT MONO (15 2910);
FORCEPROP 0 LASTPIN (25 1450) $PN L27
J 2
(15 1460);
DISPLAY 0.680851 (15 1460);
PAINT MONO (15 1460);
FORCEPROP 0 LASTPIN (25 1500) $PN L29
J 2
(15 1510);
DISPLAY 0.680851 (15 1510);
PAINT MONO (15 1510);
FORCEPROP 0 LASTPIN (25 1550) $PN L31
J 2
(15 1560);
DISPLAY 0.680851 (15 1560);
PAINT MONO (15 1560);
FORCEPROP 0 LASTPIN (25 1600) $PN L33
J 2
(15 1610);
DISPLAY 0.680851 (15 1610);
PAINT MONO (15 1610);
FORCEPROP 0 LASTPIN (25 1650) $PN L35
J 2
(15 1660);
DISPLAY 0.680851 (15 1660);
PAINT MONO (15 1660);
FORCEPROP 0 LASTPIN (25 1700) $PN L37
J 2
(15 1710);
DISPLAY 0.680851 (15 1710);
PAINT MONO (15 1710);
FORCEPROP 0 LASTPIN (25 3250) $PN N21
J 2
(15 3260);
DISPLAY 0.680851 (15 3260);
PAINT MONO (15 3260);
FORCEPROP 0 LASTPIN (25 1750) $PN L39
J 2
(15 1760);
DISPLAY 0.680851 (15 1760);
PAINT MONO (15 1760);
FORCEPROP 0 LASTPIN (25 1800) $PN L41
J 2
(15 1810);
DISPLAY 0.680851 (15 1810);
PAINT MONO (15 1810);
FORCEPROP 0 LASTPIN (25 1850) $PN L43
J 2
(15 1860);
DISPLAY 0.680851 (15 1860);
PAINT MONO (15 1860);
FORCEPROP 0 LASTPIN (25 1900) $PN L45
J 2
(15 1910);
DISPLAY 0.680851 (15 1910);
PAINT MONO (15 1910);
FORCEPROP 0 LASTPIN (25 3400) $PN N39
J 2
(15 3410);
DISPLAY 0.680851 (15 3410);
PAINT MONO (15 3410);
FORCEPROP 0 LASTPIN (25 1950) $PN L48
J 2
(15 1960);
DISPLAY 0.680851 (15 1960);
PAINT MONO (15 1960);
FORCEPROP 0 LASTPIN (25 1000) $PN L5
J 2
(15 1010);
DISPLAY 0.680851 (15 1010);
PAINT MONO (15 1010);
FORCEPROP 0 LASTPIN (25 2000) $PN L50
J 2
(15 2010);
DISPLAY 0.680851 (15 2010);
PAINT MONO (15 2010);
FORCEPROP 0 LASTPIN (25 2050) $PN L52
J 2
(15 2060);
DISPLAY 0.680851 (15 2060);
PAINT MONO (15 2060);
FORCEPROP 0 LASTPIN (25 2100) $PN L54
J 2
(15 2110);
DISPLAY 0.680851 (15 2110);
PAINT MONO (15 2110);
FORCEPROP 0 LASTPIN (25 3600) $PN N64
J 2
(15 3610);
DISPLAY 0.680851 (15 3610);
PAINT MONO (15 3610);
FORCEPROP 0 LASTPIN (25 2150) $PN L56
J 2
(15 2160);
DISPLAY 0.680851 (15 2160);
PAINT MONO (15 2160);
FORCEPROP 0 LASTPIN (25 2250) $PN L60
J 2
(15 2260);
DISPLAY 0.680851 (15 2260);
PAINT MONO (15 2260);
FORCEPROP 0 LASTPIN (25 2300) $PN L62
J 2
(15 2310);
DISPLAY 0.680851 (15 2310);
PAINT MONO (15 2310);
FORCEPROP 0 LASTPIN (25 2350) $PN L64
J 2
(15 2360);
DISPLAY 0.680851 (15 2360);
PAINT MONO (15 2360);
FORCEPROP 0 LASTPIN (25 2400) $PN L66
J 2
(15 2410);
DISPLAY 0.680851 (15 2410);
PAINT MONO (15 2410);
FORCEPROP 0 LASTPIN (25 2450) $PN L68
J 2
(15 2460);
DISPLAY 0.680851 (15 2460);
PAINT MONO (15 2460);
FORCEPROP 0 LASTPIN (25 2550) $PN L72
J 2
(15 2560);
DISPLAY 0.680851 (15 2560);
PAINT MONO (15 2560);
FORCEPROP 0 LASTPIN (25 2600) $PN L74
J 2
(15 2610);
DISPLAY 0.680851 (15 2610);
PAINT MONO (15 2610);
FORCEPROP 0 LASTPIN (25 2650) $PN L76
J 2
(15 2660);
DISPLAY 0.680851 (15 2660);
PAINT MONO (15 2660);
FORCEPROP 0 LASTPIN (25 2700) $PN L78
J 2
(15 2710);
DISPLAY 0.680851 (15 2710);
PAINT MONO (15 2710);
FORCEPROP 0 LASTPIN (25 3100) $PN M81
J 2
(15 3110);
DISPLAY 0.680851 (15 3110);
PAINT MONO (15 3110);
FORCEPROP 0 LASTPIN (25 3150) $PN M83
J 2
(15 3160);
DISPLAY 0.680851 (15 3160);
PAINT MONO (15 3160);
FORCEPROP 0 LASTPIN (25 3200) $PN N15
J 2
(15 3210);
DISPLAY 0.680851 (15 3210);
PAINT MONO (15 3210);
FORCEPROP 0 LASTPIN (25 3300) $PN N27
J 2
(15 3310);
DISPLAY 0.680851 (15 3310);
PAINT MONO (15 3310);
FORCEPROP 0 LASTPIN (25 3350) $PN N33
J 2
(15 3360);
DISPLAY 0.680851 (15 3360);
PAINT MONO (15 3360);
FORCEPROP 0 LASTPIN (25 3450) $PN N45
J 2
(15 3460);
DISPLAY 0.680851 (15 3460);
PAINT MONO (15 3460);
FORCEPROP 0 LASTPIN (25 3500) $PN N52
J 2
(15 3510);
DISPLAY 0.680851 (15 3510);
PAINT MONO (15 3510);
FORCEPROP 0 LASTPIN (25 3550) $PN N58
J 2
(15 3560);
DISPLAY 0.680851 (15 3560);
PAINT MONO (15 3560);
FORCEPROP 0 LASTPIN (25 3650) $PN N70
J 2
(15 3660);
DISPLAY 0.680851 (15 3660);
PAINT MONO (15 3660);
FORCEPROP 2 LAST CDS_LIB pure_quanta
J 0
(1225 1675);
DISPLAY INVISIBLE (1225 1675);
FORCEPROP 1 LAST NEEDS_NO_SIZE TRUE
J 0
(1225 1675);
DISPLAY 0.723404 (1225 1675);
PAINT GREEN (1225 1675);
DISPLAY INVISIBLE (1225 1675);
FORCEPROP 1 LAST CDS_LMAN_SYM_OUTLINE -1050,2150,1050,-2100
J 0
(1225 1675);
DISPLAY 0.468085 (1225 1675);
PAINT GREEN (1225 1675);
DISPLAY INVISIBLE (1225 1675);
FORCEPROP 2 LAST CDS_LOCATION U2
J 0
(175 4150);
DISPLAY 1.021277 (175 4150);
DISPLAY INVISIBLE (175 4150);
FORCEPROP 0 LAST $SEC 41
J 0
(175 4150);
DISPLAY 0.680851 (175 4150);
PAINT MONO (175 4150);
DISPLAY INVISIBLE (175 4150);
FORCEPROP 2 LAST CDS_SEC 41
J 0
(175 4150);
DISPLAY 1.021277 (175 4150);
DISPLAY INVISIBLE (175 4150);
FORCEPROP 1 LAST PATH I11
J 0
(1225 1675);
DISPLAY 0.723404 (1225 1675);
PAINT GREEN (1225 1675);
DISPLAY INVISIBLE (1225 1675);
FORCEADD SOCKET4677_AZIF0045P001C01CS..42
(4250 1725);
FORCEPROP 1 LAST PART_NUMBER DGA^7000023
J 0
(3200 3925);
DISPLAY 0.723404 (3200 3925);
PAINT GREEN (3200 3925);
DISPLAY INVISIBLE (3200 3925);
FORCEPROP 2 LAST PART_TYPE SMLF
J 0
(3200 4100);
DISPLAY 1.021277 (3200 4100);
FORCEPROP 1 LAST MATERIAL IO
J 0
(3200 3850);
DISPLAY 0.723404 (3200 3850);
PAINT GREEN (3200 3850);
FORCEPROP 2 LAST VALUE SOCKET4677_AZIF0045-P001C01CS
J 0
(3200 4050);
DISPLAY 1.021277 (3200 4050);
FORCEPROP 1 LAST $LOCATION U2
J 0
(3200 4000);
DISPLAY 0.723404 (3200 4000);
PAINT GREEN (3200 4000);
FORCEPROP 0 LASTPIN (3050 -200) $PN A11
J 2
(3040 -190);
DISPLAY 0.680851 (3040 -190);
PAINT MONO (3040 -190);
FORCEPROP 0 LASTPIN (3050 -150) $PN A13
J 2
(3040 -140);
DISPLAY 0.680851 (3040 -140);
PAINT MONO (3040 -140);
FORCEPROP 0 LASTPIN (3050 -100) $PN A17
J 2
(3040 -90);
DISPLAY 0.680851 (3040 -90);
PAINT MONO (3040 -90);
FORCEPROP 0 LASTPIN (3050 -50) $PN A19
J 2
(3040 -40);
DISPLAY 0.680851 (3040 -40);
PAINT MONO (3040 -40);
FORCEPROP 0 LASTPIN (3050 0) $PN A23
J 2
(3040 10);
DISPLAY 0.680851 (3040 10);
PAINT MONO (3040 10);
FORCEPROP 0 LASTPIN (3050 50) $PN A25
J 2
(3040 60);
DISPLAY 0.680851 (3040 60);
PAINT MONO (3040 60);
FORCEPROP 0 LASTPIN (3050 100) $PN A29
J 2
(3040 110);
DISPLAY 0.680851 (3040 110);
PAINT MONO (3040 110);
FORCEPROP 0 LASTPIN (3050 150) $PN A31
J 2
(3040 160);
DISPLAY 0.680851 (3040 160);
PAINT MONO (3040 160);
FORCEPROP 0 LASTPIN (3050 200) $PN A35
J 2
(3040 210);
DISPLAY 0.680851 (3040 210);
PAINT MONO (3040 210);
FORCEPROP 0 LASTPIN (3050 250) $PN A37
J 2
(3040 260);
DISPLAY 0.680851 (3040 260);
PAINT MONO (3040 260);
FORCEPROP 0 LASTPIN (3050 300) $PN A41
J 2
(3040 310);
DISPLAY 0.680851 (3040 310);
PAINT MONO (3040 310);
FORCEPROP 0 LASTPIN (3050 350) $PN A50
J 2
(3040 360);
DISPLAY 0.680851 (3040 360);
PAINT MONO (3040 360);
FORCEPROP 0 LASTPIN (3050 400) $PN A54
J 2
(3040 410);
DISPLAY 0.680851 (3040 410);
PAINT MONO (3040 410);
FORCEPROP 0 LASTPIN (3050 450) $PN A56
J 2
(3040 460);
DISPLAY 0.680851 (3040 460);
PAINT MONO (3040 460);
FORCEPROP 0 LASTPIN (3050 500) $PN A60
J 2
(3040 510);
DISPLAY 0.680851 (3040 510);
PAINT MONO (3040 510);
FORCEPROP 0 LASTPIN (3050 550) $PN A62
J 2
(3040 560);
DISPLAY 0.680851 (3040 560);
PAINT MONO (3040 560);
FORCEPROP 0 LASTPIN (3050 650) $PN B12
J 2
(3040 660);
DISPLAY 0.680851 (3040 660);
PAINT MONO (3040 660);
FORCEPROP 0 LASTPIN (3050 700) $PN B18
J 2
(3040 710);
DISPLAY 0.680851 (3040 710);
PAINT MONO (3040 710);
FORCEPROP 0 LASTPIN (3050 750) $PN B24
J 2
(3040 760);
DISPLAY 0.680851 (3040 760);
PAINT MONO (3040 760);
FORCEPROP 0 LASTPIN (3050 800) $PN B30
J 2
(3040 810);
DISPLAY 0.680851 (3040 810);
PAINT MONO (3040 810);
FORCEPROP 0 LASTPIN (3050 850) $PN B36
J 2
(3040 860);
DISPLAY 0.680851 (3040 860);
PAINT MONO (3040 860);
FORCEPROP 0 LASTPIN (3050 900) $PN B42
J 2
(3040 910);
DISPLAY 0.680851 (3040 910);
PAINT MONO (3040 910);
FORCEPROP 0 LASTPIN (3050 950) $PN B49
J 2
(3040 960);
DISPLAY 0.680851 (3040 960);
PAINT MONO (3040 960);
FORCEPROP 0 LASTPIN (3050 1000) $PN B55
J 2
(3040 1010);
DISPLAY 0.680851 (3040 1010);
PAINT MONO (3040 1010);
FORCEPROP 0 LASTPIN (3050 600) $PN B6
J 2
(3040 610);
DISPLAY 0.680851 (3040 610);
PAINT MONO (3040 610);
FORCEPROP 0 LASTPIN (3050 1050) $PN B61
J 2
(3040 1060);
DISPLAY 0.680851 (3040 1060);
PAINT MONO (3040 1060);
FORCEPROP 0 LASTPIN (3050 1100) $PN B67
J 2
(3040 1110);
DISPLAY 0.680851 (3040 1110);
PAINT MONO (3040 1110);
FORCEPROP 0 LASTPIN (3050 1150) $PN B75
J 2
(3040 1160);
DISPLAY 0.680851 (3040 1160);
PAINT MONO (3040 1160);
FORCEPROP 0 LASTPIN (3050 1200) $PN B83
J 2
(3040 1210);
DISPLAY 0.680851 (3040 1210);
PAINT MONO (3040 1210);
FORCEPROP 0 LASTPIN (3050 1250) $PN B87
J 2
(3040 1260);
DISPLAY 0.680851 (3040 1260);
PAINT MONO (3040 1260);
FORCEPROP 0 LASTPIN (3050 1350) $PN C39
J 2
(3040 1360);
DISPLAY 0.680851 (3040 1360);
PAINT MONO (3040 1360);
FORCEPROP 0 LASTPIN (3050 1400) $PN C45
J 2
(3040 1410);
DISPLAY 0.680851 (3040 1410);
PAINT MONO (3040 1410);
FORCEPROP 0 LASTPIN (3050 1300) $PN C5
J 2
(3040 1310);
DISPLAY 0.680851 (3040 1310);
PAINT MONO (3040 1310);
FORCEPROP 0 LASTPIN (3050 1450) $PN C52
J 2
(3040 1460);
DISPLAY 0.680851 (3040 1460);
PAINT MONO (3040 1460);
FORCEPROP 0 LASTPIN (3050 1500) $PN C72
J 2
(3040 1510);
DISPLAY 0.680851 (3040 1510);
PAINT MONO (3040 1510);
FORCEPROP 0 LASTPIN (3050 1550) $PN C74
J 2
(3040 1560);
DISPLAY 0.680851 (3040 1560);
PAINT MONO (3040 1560);
FORCEPROP 0 LASTPIN (3050 1600) $PN C78
J 2
(3040 1610);
DISPLAY 0.680851 (3040 1610);
PAINT MONO (3040 1610);
FORCEPROP 0 LASTPIN (3050 1650) $PN C80
J 2
(3040 1660);
DISPLAY 0.680851 (3040 1660);
PAINT MONO (3040 1660);
FORCEPROP 0 LASTPIN (3050 1700) $PN C82
J 2
(3040 1710);
DISPLAY 0.680851 (3040 1710);
PAINT MONO (3040 1710);
FORCEPROP 0 LASTPIN (3050 1750) $PN C86
J 2
(3040 1760);
DISPLAY 0.680851 (3040 1760);
PAINT MONO (3040 1760);
FORCEPROP 0 LASTPIN (3050 3200) $PN D63
J 2
(3040 3210);
DISPLAY 0.680851 (3040 3210);
PAINT MONO (3040 3210);
FORCEPROP 0 LASTPIN (3050 3250) $PN D65
J 2
(3040 3260);
DISPLAY 0.680851 (3040 3260);
PAINT MONO (3040 3260);
FORCEPROP 0 LASTPIN (3050 3300) $PN D67
J 2
(3040 3310);
DISPLAY 0.680851 (3040 3310);
PAINT MONO (3040 3310);
FORCEPROP 0 LASTPIN (3050 3450) $PN D79
J 2
(3040 3460);
DISPLAY 0.680851 (3040 3460);
PAINT MONO (3040 3460);
FORCEPROP 0 LASTPIN (3050 1850) $PN D8
J 2
(3040 1860);
DISPLAY 0.680851 (3040 1860);
PAINT MONO (3040 1860);
FORCEPROP 0 LASTPIN (3050 1900) $PN D10
J 2
(3040 1910);
DISPLAY 0.680851 (3040 1910);
PAINT MONO (3040 1910);
FORCEPROP 0 LASTPIN (3050 1950) $PN D12
J 2
(3040 1960);
DISPLAY 0.680851 (3040 1960);
PAINT MONO (3040 1960);
FORCEPROP 0 LASTPIN (3050 2000) $PN D14
J 2
(3040 2010);
DISPLAY 0.680851 (3040 2010);
PAINT MONO (3040 2010);
FORCEPROP 0 LASTPIN (3050 2050) $PN D16
J 2
(3040 2060);
DISPLAY 0.680851 (3040 2060);
PAINT MONO (3040 2060);
FORCEPROP 0 LASTPIN (3050 2100) $PN D18
J 2
(3040 2110);
DISPLAY 0.680851 (3040 2110);
PAINT MONO (3040 2110);
FORCEPROP 0 LASTPIN (3050 2150) $PN D20
J 2
(3040 2160);
DISPLAY 0.680851 (3040 2160);
PAINT MONO (3040 2160);
FORCEPROP 0 LASTPIN (3050 2200) $PN D22
J 2
(3040 2210);
DISPLAY 0.680851 (3040 2210);
PAINT MONO (3040 2210);
FORCEPROP 0 LASTPIN (3050 2250) $PN D24
J 2
(3040 2260);
DISPLAY 0.680851 (3040 2260);
PAINT MONO (3040 2260);
FORCEPROP 0 LASTPIN (3050 2300) $PN D26
J 2
(3040 2310);
DISPLAY 0.680851 (3040 2310);
PAINT MONO (3040 2310);
FORCEPROP 0 LASTPIN (3050 2350) $PN D28
J 2
(3040 2360);
DISPLAY 0.680851 (3040 2360);
PAINT MONO (3040 2360);
FORCEPROP 0 LASTPIN (3050 2400) $PN D30
J 2
(3040 2410);
DISPLAY 0.680851 (3040 2410);
PAINT MONO (3040 2410);
FORCEPROP 0 LASTPIN (3050 2450) $PN D32
J 2
(3040 2460);
DISPLAY 0.680851 (3040 2460);
PAINT MONO (3040 2460);
FORCEPROP 0 LASTPIN (3050 2500) $PN D34
J 2
(3040 2510);
DISPLAY 0.680851 (3040 2510);
PAINT MONO (3040 2510);
FORCEPROP 0 LASTPIN (3050 2550) $PN D36
J 2
(3040 2560);
DISPLAY 0.680851 (3040 2560);
PAINT MONO (3040 2560);
FORCEPROP 0 LASTPIN (3050 2600) $PN D38
J 2
(3040 2610);
DISPLAY 0.680851 (3040 2610);
PAINT MONO (3040 2610);
FORCEPROP 0 LASTPIN (3050 2650) $PN D40
J 2
(3040 2660);
DISPLAY 0.680851 (3040 2660);
PAINT MONO (3040 2660);
FORCEPROP 0 LASTPIN (3050 2700) $PN D42
J 2
(3040 2710);
DISPLAY 0.680851 (3040 2710);
PAINT MONO (3040 2710);
FORCEPROP 0 LASTPIN (3050 2750) $PN D44
J 2
(3040 2760);
DISPLAY 0.680851 (3040 2760);
PAINT MONO (3040 2760);
FORCEPROP 0 LASTPIN (3050 2800) $PN D47
J 2
(3040 2810);
DISPLAY 0.680851 (3040 2810);
PAINT MONO (3040 2810);
FORCEPROP 0 LASTPIN (3050 2850) $PN D49
J 2
(3040 2860);
DISPLAY 0.680851 (3040 2860);
PAINT MONO (3040 2860);
FORCEPROP 0 LASTPIN (3050 2900) $PN D51
J 2
(3040 2910);
DISPLAY 0.680851 (3040 2910);
PAINT MONO (3040 2910);
FORCEPROP 0 LASTPIN (3050 2950) $PN D53
J 2
(3040 2960);
DISPLAY 0.680851 (3040 2960);
PAINT MONO (3040 2960);
FORCEPROP 0 LASTPIN (3050 3000) $PN D55
J 2
(3040 3010);
DISPLAY 0.680851 (3040 3010);
PAINT MONO (3040 3010);
FORCEPROP 0 LASTPIN (3050 3050) $PN D57
J 2
(3040 3060);
DISPLAY 0.680851 (3040 3060);
PAINT MONO (3040 3060);
FORCEPROP 0 LASTPIN (3050 3100) $PN D59
J 2
(3040 3110);
DISPLAY 0.680851 (3040 3110);
PAINT MONO (3040 3110);
FORCEPROP 0 LASTPIN (3050 1800) $PN D6
J 2
(3040 1810);
DISPLAY 0.680851 (3040 1810);
PAINT MONO (3040 1810);
FORCEPROP 0 LASTPIN (3050 3150) $PN D61
J 2
(3040 3160);
DISPLAY 0.680851 (3040 3160);
PAINT MONO (3040 3160);
FORCEPROP 0 LASTPIN (3050 3350) $PN D69
J 2
(3040 3360);
DISPLAY 0.680851 (3040 3360);
PAINT MONO (3040 3360);
FORCEPROP 0 LASTPIN (3050 3400) $PN D71
J 2
(3040 3410);
DISPLAY 0.680851 (3040 3410);
PAINT MONO (3040 3410);
FORCEPROP 0 LASTPIN (3050 3500) $PN D81
J 2
(3040 3510);
DISPLAY 0.680851 (3040 3510);
PAINT MONO (3040 3510);
FORCEPROP 0 LASTPIN (3050 3550) $PN D83
J 2
(3040 3560);
DISPLAY 0.680851 (3040 3560);
PAINT MONO (3040 3560);
FORCEPROP 0 LASTPIN (3050 3600) $PN E5
J 2
(3040 3610);
DISPLAY 0.680851 (3040 3610);
PAINT MONO (3040 3610);
FORCEPROP 0 LASTPIN (3050 3650) $PN E39
J 2
(3040 3660);
DISPLAY 0.680851 (3040 3660);
PAINT MONO (3040 3660);
FORCEPROP 2 LAST CDS_LIB pure_quanta
J 0
(4250 1725);
DISPLAY INVISIBLE (4250 1725);
FORCEPROP 1 LAST NEEDS_NO_SIZE TRUE
J 0
(4250 1725);
DISPLAY 0.723404 (4250 1725);
PAINT GREEN (4250 1725);
DISPLAY INVISIBLE (4250 1725);
FORCEPROP 1 LAST CDS_LMAN_SYM_OUTLINE -1050,2100,1050,-2050
J 0
(4250 1725);
DISPLAY 0.468085 (4250 1725);
PAINT GREEN (4250 1725);
DISPLAY INVISIBLE (4250 1725);
FORCEPROP 2 LAST CDS_LOCATION U2
J 0
(3200 4150);
DISPLAY 1.021277 (3200 4150);
DISPLAY INVISIBLE (3200 4150);
FORCEPROP 0 LAST $SEC 42
J 0
(3200 4150);
DISPLAY 0.680851 (3200 4150);
PAINT MONO (3200 4150);
DISPLAY INVISIBLE (3200 4150);
FORCEPROP 2 LAST CDS_SEC 42
J 0
(3200 4150);
DISPLAY 1.021277 (3200 4150);
DISPLAY INVISIBLE (3200 4150);
FORCEPROP 1 LAST PATH I12
J 0
(4250 1725);
DISPLAY 0.723404 (4250 1725);
PAINT GREEN (4250 1725);
DISPLAY INVISIBLE (4250 1725);
FORCEADD UNIVERSAL_GND..1
(-375 -850);
FORCEPROP 3 LASTPIN (-375 -800) SIG_NAME GND\g
J 0
(-365 -790);
DISPLAY 0.659574 (-365 -790);
PAINT MONO (-365 -790);
DISPLAY INVISIBLE (-365 -790);
FORCEPROP 2 LAST CDS_LIB logical_power
J 0
(-375 -850);
PAINT MONO (-375 -850);
DISPLAY INVISIBLE (-375 -850);
FORCEPROP 1 LAST HDL_POWER GND
J 1
(-350 -925);
DISPLAY 0.872340 (-350 -925);
PAINT GREEN (-350 -925);
DISPLAY INVISIBLE (-350 -925);
FORCEPROP 1 LAST PATH I3
J 0
(-300 -850);
DISPLAY 0.872340 (-300 -850);
PAINT AQUA (-300 -850);
DISPLAY INVISIBLE (-300 -850);
FORCEADD UNIVERSAL_GND..1
(-225 -850);
FORCEPROP 3 LASTPIN (-225 -800) SIG_NAME GND\g
J 0
(-215 -790);
DISPLAY 0.659574 (-215 -790);
PAINT MONO (-215 -790);
DISPLAY INVISIBLE (-215 -790);
FORCEPROP 2 LAST CDS_LIB logical_power
J 0
(-225 -850);
PAINT MONO (-225 -850);
DISPLAY INVISIBLE (-225 -850);
FORCEPROP 1 LAST HDL_POWER GND
J 1
(-200 -925);
DISPLAY 0.872340 (-200 -925);
PAINT GREEN (-200 -925);
DISPLAY INVISIBLE (-200 -925);
FORCEPROP 1 LAST PATH I4
J 0
(-150 -850);
DISPLAY 0.872340 (-150 -850);
PAINT AQUA (-150 -850);
DISPLAY INVISIBLE (-150 -850);
FORCEADD UNIVERSAL_GND..1
(2675 -850);
FORCEPROP 3 LASTPIN (2675 -800) SIG_NAME GND\g
J 0
(2685 -790);
DISPLAY 0.659574 (2685 -790);
PAINT MONO (2685 -790);
DISPLAY INVISIBLE (2685 -790);
FORCEPROP 2 LAST CDS_LIB logical_power
J 0
(2675 -850);
PAINT MONO (2675 -850);
DISPLAY INVISIBLE (2675 -850);
FORCEPROP 1 LAST HDL_POWER GND
J 1
(2700 -925);
DISPLAY 0.872340 (2700 -925);
PAINT GREEN (2700 -925);
DISPLAY INVISIBLE (2700 -925);
FORCEPROP 1 LAST PATH I6
J 0
(2750 -850);
DISPLAY 0.872340 (2750 -850);
PAINT AQUA (2750 -850);
DISPLAY INVISIBLE (2750 -850);
FORCEADD UNIVERSAL_GND..1
(2800 -850);
FORCEPROP 3 LASTPIN (2800 -800) SIG_NAME GND\g
J 0
(2810 -790);
DISPLAY 0.659574 (2810 -790);
PAINT MONO (2810 -790);
DISPLAY INVISIBLE (2810 -790);
FORCEPROP 2 LAST CDS_LIB logical_power
J 0
(2800 -850);
PAINT MONO (2800 -850);
DISPLAY INVISIBLE (2800 -850);
FORCEPROP 1 LAST HDL_POWER GND
J 1
(2825 -925);
DISPLAY 0.872340 (2825 -925);
PAINT GREEN (2825 -925);
DISPLAY INVISIBLE (2825 -925);
FORCEPROP 1 LAST PATH I7
J 0
(2875 -850);
DISPLAY 0.872340 (2875 -850);
PAINT AQUA (2875 -850);
DISPLAY INVISIBLE (2875 -850);
FORCEADD QUANTA_TITLE_BLOCK_C..1
(5675 -1700);
FORCEPROP 0 LAST CDS_CON_LAST_MODIFIED Fri Aug 25 14:00:25 2023
J 0
(3790 -1685);
PAINT MONO (3790 -1685);
DISPLAY INVISIBLE (3790 -1685);
FORCEPROP 1 LAST CUSTOM_TXT_CDS <CON_LAST_MODIFIED>
J 0
(3790 -1685);
DISPLAY 0.978723 (3790 -1685);
FORCEPROP 2 LAST CUSTOM_TXT_CDS <XR_PAGE_TITLE>
J 0
(-2215 3550);
DISPLAY 0.638298 (-2215 3550);
PAINT PINK (-2215 3550);
DISPLAY INVISIBLE (-2215 3550);
FORCEPROP 2 LAST CUSTOM_TXT_CDS <Q_NUMBER>
J 0
(4272 -1597);
DISPLAY 1.212766 (4272 -1597);
FORCEPROP 1 LAST CUSTOM_TXT_CDS <NAME_2>
J 0
(2500 -1650);
FORCEPROP 1 LAST CUSTOM_TXT_CDS <NAME_1>
J 0
(2500 -1525);
FORCEPROP 1 LAST CUSTOM_TXT_CDS <Q_PROJ>
J 0
(3293 -1598);
DISPLAY 1.212766 (3293 -1598);
FORCEPROP 1 LAST CUSTOM_TXT_CDS <Q_REV>
J 0
(5491 -1597);
DISPLAY 1.212766 (5491 -1597);
FORCEPROP 1 LAST CUSTOM_TXT_CDS <CON_PAGE_NUM> OF <CON_TOTAL_PAGES>
J 0
(5229 -1682);
DISPLAY 0.978723 (5229 -1682);
FORCEPROP 1 LAST Q_TITLE SPR CPU0 POWER - GND (30 OF 30)
J 0
(-3691 -1674);
DISPLAY 1.957447 (-3691 -1674);
PAINT GREEN (-3691 -1674);
FORCEPROP 1 LAST Q_DEPT 
J 1
(1912 -1651);
DISPLAY 1.957447 (1912 -1651);
PAINT GREEN (1912 -1651);
FORCEPROP 2 LAST PAGE_BORDER TRUE
J 0
(-2215 3550);
DISPLAY 0.638298 (-2215 3550);
PAINT PINK (-2215 3550);
DISPLAY INVISIBLE (-2215 3550);
FORCEPROP 1 LAST CDS_LMAN_SYM_OUTLINE -9475,6775,100,-125
J 0
(5675 -1700);
DISPLAY 0.468085 (5675 -1700);
PAINT GREEN (5675 -1700);
DISPLAY INVISIBLE (5675 -1700);
FORCEPROP 2 LAST CDS_LIB pure_quanta
J 0
(5675 -1700);
PAINT MONO (5675 -1700);
DISPLAY INVISIBLE (5675 -1700);
FORCEPROP 2 LAST CDS_XR_PAGE_TITLE CR-42 : @S9S_MB_2U_LIB.S9S_MB_2U(SCH_1):PAGE42
J 0
(-2215 3550);
DISPLAY 0.638298 (-2215 3550);
PAINT PINK (-2215 3550);
DISPLAY INVISIBLE (-2215 3550);
FORCEPROP 1 LAST COMMENT_BODY TRUE
J 0
(5687 -1713);
DISPLAY 0.978723 (5687 -1713);
PAINT GREEN (5687 -1713);
DISPLAY INVISIBLE (5687 -1713);
WIRE 16 -1 (2800 -200)(2800 -800);
WIRE 16 -1 (2800 -150)(2800 -200);
WIRE 16 -1 (2800 -200)(3050 -200);
WIRE 16 -1 (2675 -100)(2675 -800);
WIRE 16 -1 (2675 -50)(2675 -100);
WIRE 16 -1 (2425 -100)(2675 -100);
WIRE 16 -1 (-225 -300)(-225 -800);
WIRE 16 -1 (-225 -250)(-225 -300);
WIRE 16 -1 (-225 -300)(25 -300);
WIRE 16 -1 (-375 -300)(-375 -800);
WIRE 16 -1 (-375 -250)(-375 -300);
WIRE 16 -1 (-625 -300)(-375 -300);
WIRE 16 -1 (-3275 -300)(-3275 -800);
WIRE 16 -1 (-3275 -250)(-3275 -300);
WIRE 16 -1 (-3275 -300)(-3025 -300);
WIRE 16 -1 (25 3650)(-225 3650);
WIRE 16 -1 (-225 3650)(-225 3600);
WIRE 16 -1 (25 3600)(-225 3600);
WIRE 16 -1 (-225 3600)(-225 3550);
WIRE 16 -1 (25 3550)(-225 3550);
WIRE 16 -1 (-225 3550)(-225 3500);
WIRE 16 -1 (25 3500)(-225 3500);
WIRE 16 -1 (-225 3500)(-225 3450);
WIRE 16 -1 (25 3450)(-225 3450);
WIRE 16 -1 (-225 3450)(-225 3400);
WIRE 16 -1 (25 3400)(-225 3400);
WIRE 16 -1 (-225 3400)(-225 3350);
WIRE 16 -1 (25 3350)(-225 3350);
WIRE 16 -1 (-225 3350)(-225 3300);
WIRE 16 -1 (25 3300)(-225 3300);
WIRE 16 -1 (-225 3300)(-225 3250);
WIRE 16 -1 (25 3250)(-225 3250);
WIRE 16 -1 (-225 3250)(-225 3200);
WIRE 16 -1 (25 3200)(-225 3200);
WIRE 16 -1 (-225 3200)(-225 3150);
WIRE 16 -1 (25 3150)(-225 3150);
WIRE 16 -1 (-225 3150)(-225 3100);
WIRE 16 -1 (25 3100)(-225 3100);
WIRE 16 -1 (-225 3100)(-225 3050);
WIRE 16 -1 (25 3050)(-225 3050);
WIRE 16 -1 (-225 3050)(-225 3000);
WIRE 16 -1 (25 3000)(-225 3000);
WIRE 16 -1 (-225 3000)(-225 2950);
WIRE 16 -1 (-225 2950)(25 2950);
WIRE 16 -1 (-225 2950)(-225 2900);
WIRE 16 -1 (-225 2900)(25 2900);
WIRE 16 -1 (-225 2900)(-225 2850);
WIRE 16 -1 (-225 2850)(25 2850);
WIRE 16 -1 (-225 2850)(-225 2800);
WIRE 16 -1 (-225 2800)(25 2800);
WIRE 16 -1 (-225 2800)(-225 2750);
WIRE 16 -1 (-225 2750)(25 2750);
WIRE 16 -1 (-225 2750)(-225 2700);
WIRE 16 -1 (-225 2700)(25 2700);
WIRE 16 -1 (-225 2700)(-225 2650);
WIRE 16 -1 (-225 2650)(25 2650);
WIRE 16 -1 (-225 2650)(-225 2600);
WIRE 16 -1 (-225 2600)(25 2600);
WIRE 16 -1 (-225 2600)(-225 2550);
WIRE 16 -1 (-225 2550)(25 2550);
WIRE 16 -1 (-225 2550)(-225 2500);
WIRE 16 -1 (-225 2500)(25 2500);
WIRE 16 -1 (-225 2500)(-225 2450);
WIRE 16 -1 (-225 2450)(25 2450);
WIRE 16 -1 (-225 2450)(-225 2400);
WIRE 16 -1 (-225 2400)(25 2400);
WIRE 16 -1 (-225 2400)(-225 2350);
WIRE 16 -1 (-225 2350)(25 2350);
WIRE 16 -1 (-225 2350)(-225 2300);
WIRE 16 -1 (-225 2300)(25 2300);
WIRE 16 -1 (-225 2300)(-225 2250);
WIRE 16 -1 (-225 2250)(25 2250);
WIRE 16 -1 (-225 2250)(-225 2200);
WIRE 16 -1 (-225 2200)(25 2200);
WIRE 16 -1 (-225 2200)(-225 2150);
WIRE 16 -1 (-225 2150)(25 2150);
WIRE 16 -1 (-225 2150)(-225 2100);
WIRE 16 -1 (-225 2100)(25 2100);
WIRE 16 -1 (-225 2100)(-225 2050);
WIRE 16 -1 (-225 2050)(25 2050);
WIRE 16 -1 (-225 2050)(-225 2000);
WIRE 16 -1 (-225 2000)(25 2000);
WIRE 16 -1 (-225 2000)(-225 1950);
WIRE 16 -1 (-225 1950)(25 1950);
WIRE 16 -1 (-225 1950)(-225 1900);
WIRE 16 -1 (-225 1900)(25 1900);
WIRE 16 -1 (-225 1900)(-225 1850);
WIRE 16 -1 (-225 1850)(25 1850);
WIRE 16 -1 (-225 1850)(-225 1800);
WIRE 16 -1 (-225 1800)(25 1800);
WIRE 16 -1 (-225 1800)(-225 1750);
WIRE 16 -1 (-225 1750)(25 1750);
WIRE 16 -1 (-225 1750)(-225 1700);
WIRE 16 -1 (-225 1700)(25 1700);
WIRE 16 -1 (-225 1700)(-225 1650);
WIRE 16 -1 (-225 1650)(25 1650);
WIRE 16 -1 (-225 1650)(-225 1600);
WIRE 16 -1 (25 1600)(-225 1600);
WIRE 16 -1 (-225 1600)(-225 1550);
WIRE 16 -1 (-225 1550)(25 1550);
WIRE 16 -1 (-225 1550)(-225 1500);
WIRE 16 -1 (-225 1500)(25 1500);
WIRE 16 -1 (-225 1500)(-225 1450);
WIRE 16 -1 (-225 1450)(25 1450);
WIRE 16 -1 (-225 1450)(-225 1400);
WIRE 16 -1 (-225 1400)(25 1400);
WIRE 16 -1 (-225 1400)(-225 1350);
WIRE 16 -1 (-225 1350)(25 1350);
WIRE 16 -1 (-225 1350)(-225 1300);
WIRE 16 -1 (-225 1300)(25 1300);
WIRE 16 -1 (-225 1300)(-225 1250);
WIRE 16 -1 (-225 1250)(25 1250);
WIRE 16 -1 (-225 1250)(-225 1200);
WIRE 16 -1 (-225 1200)(25 1200);
WIRE 16 -1 (-225 1200)(-225 1150);
WIRE 16 -1 (-225 1150)(25 1150);
WIRE 16 -1 (-225 1150)(-225 1100);
WIRE 16 -1 (-225 1100)(25 1100);
WIRE 16 -1 (-225 1100)(-225 1050);
WIRE 16 -1 (-225 1050)(25 1050);
WIRE 16 -1 (-225 1050)(-225 1000);
WIRE 16 -1 (-225 1000)(25 1000);
WIRE 16 -1 (-225 1000)(-225 950);
WIRE 16 -1 (-225 950)(25 950);
WIRE 16 -1 (-225 950)(-225 900);
WIRE 16 -1 (-225 900)(25 900);
WIRE 16 -1 (-225 900)(-225 850);
WIRE 16 -1 (-225 850)(25 850);
WIRE 16 -1 (-225 850)(-225 800);
WIRE 16 -1 (-225 800)(25 800);
WIRE 16 -1 (-225 800)(-225 750);
WIRE 16 -1 (-225 750)(25 750);
WIRE 16 -1 (-225 750)(-225 700);
WIRE 16 -1 (-225 700)(25 700);
WIRE 16 -1 (-225 700)(-225 650);
WIRE 16 -1 (-225 650)(25 650);
WIRE 16 -1 (-225 650)(-225 600);
WIRE 16 -1 (25 600)(-225 600);
WIRE 16 -1 (-225 600)(-225 550);
WIRE 16 -1 (-225 550)(25 550);
WIRE 16 -1 (-225 550)(-225 500);
WIRE 16 -1 (-225 500)(25 500);
WIRE 16 -1 (-225 500)(-225 450);
WIRE 16 -1 (-225 450)(25 450);
WIRE 16 -1 (-225 450)(-225 400);
WIRE 16 -1 (-225 400)(25 400);
WIRE 16 -1 (-225 400)(-225 350);
WIRE 16 -1 (-225 350)(25 350);
WIRE 16 -1 (-225 350)(-225 300);
WIRE 16 -1 (25 300)(-225 300);
WIRE 16 -1 (-225 300)(-225 250);
WIRE 16 -1 (-225 250)(25 250);
WIRE 16 -1 (-225 250)(-225 200);
WIRE 16 -1 (-225 200)(25 200);
WIRE 16 -1 (-225 200)(-225 150);
WIRE 16 -1 (-225 150)(25 150);
WIRE 16 -1 (-225 150)(-225 100);
WIRE 16 -1 (-225 100)(25 100);
WIRE 16 -1 (-225 100)(-225 50);
WIRE 16 -1 (-225 50)(25 50);
WIRE 16 -1 (-225 50)(-225 0);
WIRE 16 -1 (-225 0)(25 0);
WIRE 16 -1 (-225 0)(-225 -50);
WIRE 16 -1 (25 -50)(-225 -50);
WIRE 16 -1 (-225 -50)(-225 -100);
WIRE 16 -1 (-225 -100)(25 -100);
WIRE 16 -1 (-225 -100)(-225 -150);
WIRE 16 -1 (-225 -150)(25 -150);
WIRE 16 -1 (-225 -150)(-225 -200);
WIRE 16 -1 (-225 -200)(25 -200);
WIRE 16 -1 (-225 -200)(-225 -250);
WIRE 16 -1 (-225 -250)(25 -250);
WIRE 16 -1 (2675 3650)(2425 3650);
WIRE 16 -1 (2675 3600)(2425 3600);
WIRE 16 -1 (2675 3650)(2675 3600);
WIRE 16 -1 (2675 3550)(2425 3550);
WIRE 16 -1 (2675 3600)(2675 3550);
WIRE 16 -1 (2675 3500)(2425 3500);
WIRE 16 -1 (2675 3550)(2675 3500);
WIRE 16 -1 (2425 3450)(2675 3450);
WIRE 16 -1 (2675 3450)(2675 3500);
WIRE 16 -1 (2675 3400)(2425 3400);
WIRE 16 -1 (2675 3400)(2675 3450);
WIRE 16 -1 (2675 3350)(2425 3350);
WIRE 16 -1 (2675 3400)(2675 3350);
WIRE 16 -1 (2675 3300)(2425 3300);
WIRE 16 -1 (2675 3350)(2675 3300);
WIRE 16 -1 (2675 3250)(2425 3250);
WIRE 16 -1 (2675 3300)(2675 3250);
WIRE 16 -1 (2675 3200)(2425 3200);
WIRE 16 -1 (2675 3250)(2675 3200);
WIRE 16 -1 (2675 3150)(2425 3150);
WIRE 16 -1 (2675 3200)(2675 3150);
WIRE 16 -1 (2675 3100)(2425 3100);
WIRE 16 -1 (2675 3150)(2675 3100);
WIRE 16 -1 (2675 3050)(2425 3050);
WIRE 16 -1 (2675 3100)(2675 3050);
WIRE 16 -1 (2675 3000)(2425 3000);
WIRE 16 -1 (2675 3050)(2675 3000);
WIRE 16 -1 (2425 2950)(2675 2950);
WIRE 16 -1 (2675 3000)(2675 2950);
WIRE 16 -1 (2425 2900)(2675 2900);
WIRE 16 -1 (2675 2950)(2675 2900);
WIRE 16 -1 (2425 2850)(2675 2850);
WIRE 16 -1 (2675 2900)(2675 2850);
WIRE 16 -1 (2425 2800)(2675 2800);
WIRE 16 -1 (2675 2850)(2675 2800);
WIRE 16 -1 (2425 2750)(2675 2750);
WIRE 16 -1 (2675 2800)(2675 2750);
WIRE 16 -1 (2425 2700)(2675 2700);
WIRE 16 -1 (2675 2750)(2675 2700);
WIRE 16 -1 (2425 2650)(2675 2650);
WIRE 16 -1 (2675 2700)(2675 2650);
WIRE 16 -1 (2425 2600)(2675 2600);
WIRE 16 -1 (2675 2600)(2675 2650);
WIRE 16 -1 (2425 2550)(2675 2550);
WIRE 16 -1 (2675 2600)(2675 2550);
WIRE 16 -1 (2675 2500)(2425 2500);
WIRE 16 -1 (2675 2550)(2675 2500);
WIRE 16 -1 (2675 2450)(2425 2450);
WIRE 16 -1 (2675 2500)(2675 2450);
WIRE 16 -1 (2675 2400)(2425 2400);
WIRE 16 -1 (2675 2450)(2675 2400);
WIRE 16 -1 (2675 2350)(2425 2350);
WIRE 16 -1 (2675 2400)(2675 2350);
WIRE 16 -1 (2425 2300)(2675 2300);
WIRE 16 -1 (2675 2300)(2675 2350);
WIRE 16 -1 (2675 2250)(2425 2250);
WIRE 16 -1 (2675 2250)(2675 2300);
WIRE 16 -1 (2675 2200)(2425 2200);
WIRE 16 -1 (2675 2250)(2675 2200);
WIRE 16 -1 (2675 2150)(2425 2150);
WIRE 16 -1 (2675 2200)(2675 2150);
WIRE 16 -1 (2675 2100)(2425 2100);
WIRE 16 -1 (2675 2150)(2675 2100);
WIRE 16 -1 (2675 2050)(2425 2050);
WIRE 16 -1 (2675 2100)(2675 2050);
WIRE 16 -1 (2675 2000)(2425 2000);
WIRE 16 -1 (2675 2050)(2675 2000);
WIRE 16 -1 (2675 1950)(2425 1950);
WIRE 16 -1 (2675 2000)(2675 1950);
WIRE 16 -1 (2675 1900)(2425 1900);
WIRE 16 -1 (2675 1950)(2675 1900);
WIRE 16 -1 (2675 1850)(2425 1850);
WIRE 16 -1 (2675 1900)(2675 1850);
WIRE 16 -1 (2425 1800)(2675 1800);
WIRE 16 -1 (2675 1850)(2675 1800);
WIRE 16 -1 (2425 1750)(2675 1750);
WIRE 16 -1 (2675 1800)(2675 1750);
WIRE 16 -1 (2425 1700)(2675 1700);
WIRE 16 -1 (2675 1750)(2675 1700);
WIRE 16 -1 (2425 1650)(2675 1650);
WIRE 16 -1 (2675 1700)(2675 1650);
WIRE 16 -1 (2425 1600)(2675 1600);
WIRE 16 -1 (2675 1650)(2675 1600);
WIRE 16 -1 (2425 1550)(2675 1550);
WIRE 16 -1 (2675 1600)(2675 1550);
WIRE 16 -1 (2425 1500)(2675 1500);
WIRE 16 -1 (2675 1550)(2675 1500);
WIRE 16 -1 (2425 1450)(2675 1450);
WIRE 16 -1 (2675 1450)(2675 1500);
WIRE 16 -1 (2425 1400)(2675 1400);
WIRE 16 -1 (2675 1450)(2675 1400);
WIRE 16 -1 (2675 1350)(2425 1350);
WIRE 16 -1 (2675 1400)(2675 1350);
WIRE 16 -1 (2675 1300)(2425 1300);
WIRE 16 -1 (2675 1350)(2675 1300);
WIRE 16 -1 (2675 1250)(2425 1250);
WIRE 16 -1 (2675 1300)(2675 1250);
WIRE 16 -1 (2675 1200)(2425 1200);
WIRE 16 -1 (2675 1250)(2675 1200);
WIRE 16 -1 (2425 1150)(2675 1150);
WIRE 16 -1 (2675 1150)(2675 1200);
WIRE 16 -1 (2675 1100)(2425 1100);
WIRE 16 -1 (2675 1100)(2675 1150);
WIRE 16 -1 (2675 1050)(2425 1050);
WIRE 16 -1 (2675 1100)(2675 1050);
WIRE 16 -1 (2675 1000)(2425 1000);
WIRE 16 -1 (2675 1050)(2675 1000);
WIRE 16 -1 (2425 950)(2675 950);
WIRE 16 -1 (2675 1000)(2675 950);
WIRE 16 -1 (2425 900)(2675 900);
WIRE 16 -1 (2675 950)(2675 900);
WIRE 16 -1 (2425 850)(2675 850);
WIRE 16 -1 (2675 900)(2675 850);
WIRE 16 -1 (2425 800)(2675 800);
WIRE 16 -1 (2675 850)(2675 800);
WIRE 16 -1 (2425 750)(2675 750);
WIRE 16 -1 (2675 800)(2675 750);
WIRE 16 -1 (2425 700)(2675 700);
WIRE 16 -1 (2675 750)(2675 700);
WIRE 16 -1 (2425 650)(2675 650);
WIRE 16 -1 (2675 700)(2675 650);
WIRE 16 -1 (2425 600)(2675 600);
WIRE 16 -1 (2675 600)(2675 650);
WIRE 16 -1 (2425 550)(2675 550);
WIRE 16 -1 (2675 600)(2675 550);
WIRE 16 -1 (2675 500)(2425 500);
WIRE 16 -1 (2675 550)(2675 500);
WIRE 16 -1 (2675 450)(2425 450);
WIRE 16 -1 (2675 500)(2675 450);
WIRE 16 -1 (2675 400)(2425 400);
WIRE 16 -1 (2675 450)(2675 400);
WIRE 16 -1 (2675 350)(2425 350);
WIRE 16 -1 (2675 400)(2675 350);
WIRE 16 -1 (2425 300)(2675 300);
WIRE 16 -1 (2675 300)(2675 350);
WIRE 16 -1 (2675 250)(2425 250);
WIRE 16 -1 (2675 250)(2675 300);
WIRE 16 -1 (2675 200)(2425 200);
WIRE 16 -1 (2675 250)(2675 200);
WIRE 16 -1 (2675 150)(2425 150);
WIRE 16 -1 (2675 200)(2675 150);
WIRE 16 -1 (2425 100)(2675 100);
WIRE 16 -1 (2675 150)(2675 100);
WIRE 16 -1 (2425 50)(2675 50);
WIRE 16 -1 (2675 100)(2675 50);
WIRE 16 -1 (2675 50)(2675 0);
WIRE 16 -1 (2425 0)(2675 0);
WIRE 16 -1 (2675 0)(2675 -50);
WIRE 16 -1 (2425 -50)(2675 -50);
WIRE 16 -1 (3050 3650)(2800 3650);
WIRE 16 -1 (2800 3650)(2800 3600);
WIRE 16 -1 (3050 3600)(2800 3600);
WIRE 16 -1 (3050 3550)(2800 3550);
WIRE 16 -1 (2800 3600)(2800 3550);
WIRE 16 -1 (2800 3550)(2800 3500);
WIRE 16 -1 (3050 3500)(2800 3500);
WIRE 16 -1 (2800 3500)(2800 3450);
WIRE 16 -1 (3050 3450)(2800 3450);
WIRE 16 -1 (2800 3450)(2800 3400);
WIRE 16 -1 (3050 3400)(2800 3400);
WIRE 16 -1 (2800 3400)(2800 3350);
WIRE 16 -1 (3050 3350)(2800 3350);
WIRE 16 -1 (2800 3350)(2800 3300);
WIRE 16 -1 (3050 3300)(2800 3300);
WIRE 16 -1 (2800 3300)(2800 3250);
WIRE 16 -1 (3050 3250)(2800 3250);
WIRE 16 -1 (2800 3250)(2800 3200);
WIRE 16 -1 (3050 3200)(2800 3200);
WIRE 16 -1 (2800 3200)(2800 3150);
WIRE 16 -1 (3050 3150)(2800 3150);
WIRE 16 -1 (2800 3150)(2800 3100);
WIRE 16 -1 (3050 3100)(2800 3100);
WIRE 16 -1 (3050 3050)(2800 3050);
WIRE 16 -1 (2800 3100)(2800 3050);
WIRE 16 -1 (2800 3050)(2800 3000);
WIRE 16 -1 (3050 3000)(2800 3000);
WIRE 16 -1 (2800 3000)(2800 2950);
WIRE 16 -1 (2800 2950)(3050 2950);
WIRE 16 -1 (2800 2950)(2800 2900);
WIRE 16 -1 (2800 2900)(3050 2900);
WIRE 16 -1 (2800 2900)(2800 2850);
WIRE 16 -1 (2800 2850)(3050 2850);
WIRE 16 -1 (2800 2850)(2800 2800);
WIRE 16 -1 (2800 2800)(3050 2800);
WIRE 16 -1 (2800 2800)(2800 2750);
WIRE 16 -1 (2800 2750)(3050 2750);
WIRE 16 -1 (2800 2750)(2800 2700);
WIRE 16 -1 (2800 2700)(3050 2700);
WIRE 16 -1 (2800 2700)(2800 2650);
WIRE 16 -1 (2800 2650)(3050 2650);
WIRE 16 -1 (2800 2650)(2800 2600);
WIRE 16 -1 (2800 2600)(3050 2600);
WIRE 16 -1 (2800 2550)(3050 2550);
WIRE 16 -1 (2800 2600)(2800 2550);
WIRE 16 -1 (2800 2550)(2800 2500);
WIRE 16 -1 (2800 2500)(3050 2500);
WIRE 16 -1 (2800 2500)(2800 2450);
WIRE 16 -1 (2800 2450)(3050 2450);
WIRE 16 -1 (2800 2450)(2800 2400);
WIRE 16 -1 (2800 2400)(3050 2400);
WIRE 16 -1 (2800 2400)(2800 2350);
WIRE 16 -1 (2800 2350)(3050 2350);
WIRE 16 -1 (2800 2350)(2800 2300);
WIRE 16 -1 (2800 2300)(3050 2300);
WIRE 16 -1 (2800 2300)(2800 2250);
WIRE 16 -1 (2800 2250)(3050 2250);
WIRE 16 -1 (2800 2250)(2800 2200);
WIRE 16 -1 (2800 2200)(3050 2200);
WIRE 16 -1 (2800 2200)(2800 2150);
WIRE 16 -1 (2800 2150)(3050 2150);
WIRE 16 -1 (2800 2150)(2800 2100);
WIRE 16 -1 (2800 2100)(3050 2100);
WIRE 16 -1 (2800 2100)(2800 2050);
WIRE 16 -1 (2800 2050)(3050 2050);
WIRE 16 -1 (2800 2000)(3050 2000);
WIRE 16 -1 (2800 2050)(2800 2000);
WIRE 16 -1 (2800 2000)(2800 1950);
WIRE 16 -1 (3050 1950)(2800 1950);
WIRE 16 -1 (2800 1950)(2800 1900);
WIRE 16 -1 (2800 1900)(3050 1900);
WIRE 16 -1 (2800 1900)(2800 1850);
WIRE 16 -1 (2800 1850)(3050 1850);
WIRE 16 -1 (2800 1850)(2800 1800);
WIRE 16 -1 (2800 1800)(3050 1800);
WIRE 16 -1 (2800 1800)(2800 1750);
WIRE 16 -1 (2800 1750)(3050 1750);
WIRE 16 -1 (2800 1750)(2800 1700);
WIRE 16 -1 (2800 1700)(3050 1700);
WIRE 16 -1 (2800 1700)(2800 1650);
WIRE 16 -1 (2800 1650)(3050 1650);
WIRE 16 -1 (2800 1650)(2800 1600);
WIRE 16 -1 (2800 1600)(3050 1600);
WIRE 16 -1 (2800 1600)(2800 1550);
WIRE 16 -1 (2800 1550)(3050 1550);
WIRE 16 -1 (2800 1500)(3050 1500);
WIRE 16 -1 (2800 1550)(2800 1500);
WIRE 16 -1 (2800 1500)(2800 1450);
WIRE 16 -1 (2800 1450)(3050 1450);
WIRE 16 -1 (2800 1450)(2800 1400);
WIRE 16 -1 (2800 1400)(3050 1400);
WIRE 16 -1 (2800 1400)(2800 1350);
WIRE 16 -1 (2800 1350)(3050 1350);
WIRE 16 -1 (2800 1350)(2800 1300);
WIRE 16 -1 (2800 1300)(3050 1300);
WIRE 16 -1 (2800 1300)(2800 1250);
WIRE 16 -1 (2800 1250)(3050 1250);
WIRE 16 -1 (2800 1250)(2800 1200);
WIRE 16 -1 (2800 1200)(3050 1200);
WIRE 16 -1 (2800 1200)(2800 1150);
WIRE 16 -1 (2800 1150)(3050 1150);
WIRE 16 -1 (2800 1150)(2800 1100);
WIRE 16 -1 (2800 1100)(3050 1100);
WIRE 16 -1 (2800 1100)(2800 1050);
WIRE 16 -1 (2800 1050)(3050 1050);
WIRE 16 -1 (2800 1000)(3050 1000);
WIRE 16 -1 (2800 1050)(2800 1000);
WIRE 16 -1 (2800 1000)(2800 950);
WIRE 16 -1 (3050 950)(2800 950);
WIRE 16 -1 (2800 950)(2800 900);
WIRE 16 -1 (2800 900)(3050 900);
WIRE 16 -1 (2800 900)(2800 850);
WIRE 16 -1 (2800 850)(3050 850);
WIRE 16 -1 (2800 850)(2800 800);
WIRE 16 -1 (2800 800)(3050 800);
WIRE 16 -1 (2800 800)(2800 750);
WIRE 16 -1 (2800 750)(3050 750);
WIRE 16 -1 (2800 750)(2800 700);
WIRE 16 -1 (2800 700)(3050 700);
WIRE 16 -1 (2800 700)(2800 650);
WIRE 16 -1 (2800 650)(3050 650);
WIRE 16 -1 (2800 650)(2800 600);
WIRE 16 -1 (3050 600)(2800 600);
WIRE 16 -1 (2800 600)(2800 550);
WIRE 16 -1 (2800 550)(3050 550);
WIRE 16 -1 (2800 500)(3050 500);
WIRE 16 -1 (2800 550)(2800 500);
WIRE 16 -1 (2800 500)(2800 450);
WIRE 16 -1 (2800 450)(3050 450);
WIRE 16 -1 (2800 450)(2800 400);
WIRE 16 -1 (2800 400)(3050 400);
WIRE 16 -1 (2800 400)(2800 350);
WIRE 16 -1 (2800 350)(3050 350);
WIRE 16 -1 (2800 350)(2800 300);
WIRE 16 -1 (3050 300)(2800 300);
WIRE 16 -1 (2800 300)(2800 250);
WIRE 16 -1 (2800 250)(3050 250);
WIRE 16 -1 (2800 250)(2800 200);
WIRE 16 -1 (2800 200)(3050 200);
WIRE 16 -1 (2800 200)(2800 150);
WIRE 16 -1 (2800 150)(3050 150);
WIRE 16 -1 (2800 150)(2800 100);
WIRE 16 -1 (2800 100)(3050 100);
WIRE 16 -1 (2800 100)(2800 50);
WIRE 16 -1 (2800 50)(3050 50);
WIRE 16 -1 (2800 50)(2800 0);
WIRE 16 -1 (2800 0)(3050 0);
WIRE 16 -1 (3050 -50)(2800 -50);
WIRE 16 -1 (2800 0)(2800 -50);
WIRE 16 -1 (2800 -50)(2800 -100);
WIRE 16 -1 (2800 -100)(3050 -100);
WIRE 16 -1 (2800 -100)(2800 -150);
WIRE 16 -1 (2800 -150)(3050 -150);
WIRE 16 -1 (-3025 3650)(-3275 3650);
WIRE 16 -1 (-3275 3650)(-3275 3600);
WIRE 16 -1 (-3025 3600)(-3275 3600);
WIRE 16 -1 (-3275 3600)(-3275 3550);
WIRE 16 -1 (-3025 3550)(-3275 3550);
WIRE 16 -1 (-3275 3550)(-3275 3500);
WIRE 16 -1 (-3025 3500)(-3275 3500);
WIRE 16 -1 (-3275 3500)(-3275 3450);
WIRE 16 -1 (-3025 3450)(-3275 3450);
WIRE 16 -1 (-3275 3450)(-3275 3400);
WIRE 16 -1 (-3025 3400)(-3275 3400);
WIRE 16 -1 (-3275 3400)(-3275 3350);
WIRE 16 -1 (-3025 3350)(-3275 3350);
WIRE 16 -1 (-3275 3350)(-3275 3300);
WIRE 16 -1 (-3025 3300)(-3275 3300);
WIRE 16 -1 (-3275 3300)(-3275 3250);
WIRE 16 -1 (-3025 3250)(-3275 3250);
WIRE 16 -1 (-3275 3250)(-3275 3200);
WIRE 16 -1 (-3025 3200)(-3275 3200);
WIRE 16 -1 (-3275 3200)(-3275 3150);
WIRE 16 -1 (-3025 3150)(-3275 3150);
WIRE 16 -1 (-3275 3150)(-3275 3100);
WIRE 16 -1 (-3025 3100)(-3275 3100);
WIRE 16 -1 (-3275 3100)(-3275 3050);
WIRE 16 -1 (-3025 3050)(-3275 3050);
WIRE 16 -1 (-3275 3050)(-3275 3000);
WIRE 16 -1 (-3025 3000)(-3275 3000);
WIRE 16 -1 (-3275 3000)(-3275 2950);
WIRE 16 -1 (-3275 2950)(-3025 2950);
WIRE 16 -1 (-3275 2950)(-3275 2900);
WIRE 16 -1 (-3275 2900)(-3025 2900);
WIRE 16 -1 (-3275 2900)(-3275 2850);
WIRE 16 -1 (-3275 2850)(-3025 2850);
WIRE 16 -1 (-3275 2850)(-3275 2800);
WIRE 16 -1 (-3275 2800)(-3025 2800);
WIRE 16 -1 (-3275 2800)(-3275 2750);
WIRE 16 -1 (-3275 2750)(-3025 2750);
WIRE 16 -1 (-3275 2750)(-3275 2700);
WIRE 16 -1 (-3275 2700)(-3025 2700);
WIRE 16 -1 (-3275 2700)(-3275 2650);
WIRE 16 -1 (-3275 2650)(-3025 2650);
WIRE 16 -1 (-3275 2650)(-3275 2600);
WIRE 16 -1 (-3275 2600)(-3025 2600);
WIRE 16 -1 (-3275 2600)(-3275 2550);
WIRE 16 -1 (-3275 2550)(-3025 2550);
WIRE 16 -1 (-3275 2550)(-3275 2500);
WIRE 16 -1 (-3275 2500)(-3025 2500);
WIRE 16 -1 (-3275 2500)(-3275 2450);
WIRE 16 -1 (-3275 2450)(-3025 2450);
WIRE 16 -1 (-3275 2450)(-3275 2400);
WIRE 16 -1 (-3275 2400)(-3025 2400);
WIRE 16 -1 (-3275 2400)(-3275 2350);
WIRE 16 -1 (-3275 2350)(-3025 2350);
WIRE 16 -1 (-3275 2350)(-3275 2300);
WIRE 16 -1 (-3275 2300)(-3025 2300);
WIRE 16 -1 (-3275 2300)(-3275 2250);
WIRE 16 -1 (-3275 2250)(-3025 2250);
WIRE 16 -1 (-3275 2250)(-3275 2200);
WIRE 16 -1 (-3275 2200)(-3025 2200);
WIRE 16 -1 (-3275 2200)(-3275 2150);
WIRE 16 -1 (-3275 2150)(-3025 2150);
WIRE 16 -1 (-3275 2150)(-3275 2100);
WIRE 16 -1 (-3275 2100)(-3025 2100);
WIRE 16 -1 (-3275 2100)(-3275 2050);
WIRE 16 -1 (-3275 2050)(-3025 2050);
WIRE 16 -1 (-3275 2000)(-3025 2000);
WIRE 16 -1 (-3275 2050)(-3275 2000);
WIRE 16 -1 (-3275 2000)(-3275 1950);
WIRE 16 -1 (-3275 1950)(-3025 1950);
WIRE 16 -1 (-3275 1950)(-3275 1900);
WIRE 16 -1 (-3275 1900)(-3025 1900);
WIRE 16 -1 (-3275 1900)(-3275 1850);
WIRE 16 -1 (-3275 1850)(-3025 1850);
WIRE 16 -1 (-3275 1850)(-3275 1800);
WIRE 16 -1 (-3275 1800)(-3025 1800);
WIRE 16 -1 (-3275 1800)(-3275 1750);
WIRE 16 -1 (-3275 1750)(-3025 1750);
WIRE 16 -1 (-3275 1750)(-3275 1700);
WIRE 16 -1 (-3275 1700)(-3025 1700);
WIRE 16 -1 (-3275 1700)(-3275 1650);
WIRE 16 -1 (-3275 1650)(-3025 1650);
WIRE 16 -1 (-3275 1650)(-3275 1600);
WIRE 16 -1 (-3025 1600)(-3275 1600);
WIRE 16 -1 (-3275 1600)(-3275 1550);
WIRE 16 -1 (-3275 1550)(-3025 1550);
WIRE 16 -1 (-3275 1550)(-3275 1500);
WIRE 16 -1 (-3275 1500)(-3025 1500);
WIRE 16 -1 (-3275 1500)(-3275 1450);
WIRE 16 -1 (-3275 1450)(-3025 1450);
WIRE 16 -1 (-3275 1450)(-3275 1400);
WIRE 16 -1 (-3275 1400)(-3025 1400);
WIRE 16 -1 (-3275 1400)(-3275 1350);
WIRE 16 -1 (-3275 1350)(-3025 1350);
WIRE 16 -1 (-3275 1350)(-3275 1300);
WIRE 16 -1 (-3275 1300)(-3025 1300);
WIRE 16 -1 (-3275 1300)(-3275 1250);
WIRE 16 -1 (-3275 1250)(-3025 1250);
WIRE 16 -1 (-3275 1250)(-3275 1200);
WIRE 16 -1 (-3275 1200)(-3025 1200);
WIRE 16 -1 (-3275 1200)(-3275 1150);
WIRE 16 -1 (-3275 1150)(-3025 1150);
WIRE 16 -1 (-3275 1150)(-3275 1100);
WIRE 16 -1 (-3275 1100)(-3025 1100);
WIRE 16 -1 (-3275 1100)(-3275 1050);
WIRE 16 -1 (-3275 1050)(-3025 1050);
WIRE 16 -1 (-3275 1050)(-3275 1000);
WIRE 16 -1 (-3275 1000)(-3025 1000);
WIRE 16 -1 (-3275 1000)(-3275 950);
WIRE 16 -1 (-3275 950)(-3025 950);
WIRE 16 -1 (-3275 950)(-3275 900);
WIRE 16 -1 (-3275 900)(-3025 900);
WIRE 16 -1 (-3275 900)(-3275 850);
WIRE 16 -1 (-3275 850)(-3025 850);
WIRE 16 -1 (-3275 850)(-3275 800);
WIRE 16 -1 (-3275 800)(-3025 800);
WIRE 16 -1 (-3275 800)(-3275 750);
WIRE 16 -1 (-3275 750)(-3025 750);
WIRE 16 -1 (-3275 750)(-3275 700);
WIRE 16 -1 (-3275 700)(-3025 700);
WIRE 16 -1 (-3275 700)(-3275 650);
WIRE 16 -1 (-3275 650)(-3025 650);
WIRE 16 -1 (-3275 650)(-3275 600);
WIRE 16 -1 (-3025 600)(-3275 600);
WIRE 16 -1 (-3275 600)(-3275 550);
WIRE 16 -1 (-3275 550)(-3025 550);
WIRE 16 -1 (-3275 550)(-3275 500);
WIRE 16 -1 (-3275 500)(-3025 500);
WIRE 16 -1 (-3275 500)(-3275 450);
WIRE 16 -1 (-3275 450)(-3025 450);
WIRE 16 -1 (-3275 450)(-3275 400);
WIRE 16 -1 (-3275 400)(-3025 400);
WIRE 16 -1 (-3275 400)(-3275 350);
WIRE 16 -1 (-3275 350)(-3025 350);
WIRE 16 -1 (-3275 350)(-3275 300);
WIRE 16 -1 (-3025 300)(-3275 300);
WIRE 16 -1 (-3275 300)(-3275 250);
WIRE 16 -1 (-3275 250)(-3025 250);
WIRE 16 -1 (-3275 250)(-3275 200);
WIRE 16 -1 (-3275 200)(-3025 200);
WIRE 16 -1 (-3275 200)(-3275 150);
WIRE 16 -1 (-3275 150)(-3025 150);
WIRE 16 -1 (-3275 150)(-3275 100);
WIRE 16 -1 (-3275 100)(-3025 100);
WIRE 16 -1 (-3275 100)(-3275 50);
WIRE 16 -1 (-3275 50)(-3025 50);
WIRE 16 -1 (-3275 50)(-3275 0);
WIRE 16 -1 (-3275 0)(-3025 0);
WIRE 16 -1 (-3025 -50)(-3275 -50);
WIRE 16 -1 (-3275 0)(-3275 -50);
WIRE 16 -1 (-3275 -50)(-3275 -100);
WIRE 16 -1 (-3275 -100)(-3025 -100);
WIRE 16 -1 (-3275 -100)(-3275 -150);
WIRE 16 -1 (-3275 -150)(-3025 -150);
WIRE 16 -1 (-3275 -150)(-3275 -200);
WIRE 16 -1 (-3275 -200)(-3025 -200);
WIRE 16 -1 (-3275 -200)(-3275 -250);
WIRE 16 -1 (-3275 -250)(-3025 -250);
WIRE 16 -1 (-375 3650)(-625 3650);
WIRE 16 -1 (-375 3600)(-625 3600);
WIRE 16 -1 (-375 3650)(-375 3600);
WIRE 16 -1 (-375 3550)(-625 3550);
WIRE 16 -1 (-375 3600)(-375 3550);
WIRE 16 -1 (-375 3500)(-625 3500);
WIRE 16 -1 (-375 3550)(-375 3500);
WIRE 16 -1 (-625 3450)(-375 3450);
WIRE 16 -1 (-375 3450)(-375 3500);
WIRE 16 -1 (-375 3400)(-625 3400);
WIRE 16 -1 (-375 3400)(-375 3450);
WIRE 16 -1 (-375 3350)(-625 3350);
WIRE 16 -1 (-375 3400)(-375 3350);
WIRE 16 -1 (-375 3300)(-625 3300);
WIRE 16 -1 (-375 3350)(-375 3300);
WIRE 16 -1 (-375 3250)(-625 3250);
WIRE 16 -1 (-375 3300)(-375 3250);
WIRE 16 -1 (-375 3200)(-625 3200);
WIRE 16 -1 (-375 3250)(-375 3200);
WIRE 16 -1 (-375 3150)(-625 3150);
WIRE 16 -1 (-375 3200)(-375 3150);
WIRE 16 -1 (-375 3100)(-625 3100);
WIRE 16 -1 (-375 3150)(-375 3100);
WIRE 16 -1 (-375 3050)(-625 3050);
WIRE 16 -1 (-375 3100)(-375 3050);
WIRE 16 -1 (-375 3000)(-625 3000);
WIRE 16 -1 (-375 3050)(-375 3000);
WIRE 16 -1 (-625 2950)(-375 2950);
WIRE 16 -1 (-375 3000)(-375 2950);
WIRE 16 -1 (-625 2900)(-375 2900);
WIRE 16 -1 (-375 2950)(-375 2900);
WIRE 16 -1 (-625 2850)(-375 2850);
WIRE 16 -1 (-375 2900)(-375 2850);
WIRE 16 -1 (-625 2800)(-375 2800);
WIRE 16 -1 (-375 2850)(-375 2800);
WIRE 16 -1 (-625 2750)(-375 2750);
WIRE 16 -1 (-375 2800)(-375 2750);
WIRE 16 -1 (-625 2700)(-375 2700);
WIRE 16 -1 (-375 2750)(-375 2700);
WIRE 16 -1 (-625 2650)(-375 2650);
WIRE 16 -1 (-375 2700)(-375 2650);
WIRE 16 -1 (-625 2600)(-375 2600);
WIRE 16 -1 (-375 2600)(-375 2650);
WIRE 16 -1 (-625 2550)(-375 2550);
WIRE 16 -1 (-375 2600)(-375 2550);
WIRE 16 -1 (-375 2500)(-625 2500);
WIRE 16 -1 (-375 2550)(-375 2500);
WIRE 16 -1 (-375 2450)(-625 2450);
WIRE 16 -1 (-375 2500)(-375 2450);
WIRE 16 -1 (-375 2400)(-625 2400);
WIRE 16 -1 (-375 2450)(-375 2400);
WIRE 16 -1 (-375 2350)(-625 2350);
WIRE 16 -1 (-375 2400)(-375 2350);
WIRE 16 -1 (-625 2300)(-375 2300);
WIRE 16 -1 (-375 2300)(-375 2350);
WIRE 16 -1 (-375 2250)(-625 2250);
WIRE 16 -1 (-375 2250)(-375 2300);
WIRE 16 -1 (-375 2200)(-625 2200);
WIRE 16 -1 (-375 2250)(-375 2200);
WIRE 16 -1 (-375 2150)(-625 2150);
WIRE 16 -1 (-375 2200)(-375 2150);
WIRE 16 -1 (-375 2100)(-625 2100);
WIRE 16 -1 (-375 2150)(-375 2100);
WIRE 16 -1 (-375 2050)(-625 2050);
WIRE 16 -1 (-375 2100)(-375 2050);
WIRE 16 -1 (-375 2000)(-625 2000);
WIRE 16 -1 (-375 2050)(-375 2000);
WIRE 16 -1 (-375 1950)(-625 1950);
WIRE 16 -1 (-375 2000)(-375 1950);
WIRE 16 -1 (-375 1900)(-625 1900);
WIRE 16 -1 (-375 1950)(-375 1900);
WIRE 16 -1 (-375 1850)(-625 1850);
WIRE 16 -1 (-375 1900)(-375 1850);
WIRE 16 -1 (-625 1800)(-375 1800);
WIRE 16 -1 (-375 1850)(-375 1800);
WIRE 16 -1 (-625 1750)(-375 1750);
WIRE 16 -1 (-375 1800)(-375 1750);
WIRE 16 -1 (-625 1700)(-375 1700);
WIRE 16 -1 (-375 1750)(-375 1700);
WIRE 16 -1 (-625 1650)(-375 1650);
WIRE 16 -1 (-375 1700)(-375 1650);
WIRE 16 -1 (-625 1600)(-375 1600);
WIRE 16 -1 (-375 1650)(-375 1600);
WIRE 16 -1 (-625 1550)(-375 1550);
WIRE 16 -1 (-375 1600)(-375 1550);
WIRE 16 -1 (-625 1500)(-375 1500);
WIRE 16 -1 (-375 1550)(-375 1500);
WIRE 16 -1 (-625 1450)(-375 1450);
WIRE 16 -1 (-375 1450)(-375 1500);
WIRE 16 -1 (-625 1400)(-375 1400);
WIRE 16 -1 (-375 1450)(-375 1400);
WIRE 16 -1 (-375 1350)(-625 1350);
WIRE 16 -1 (-375 1400)(-375 1350);
WIRE 16 -1 (-375 1300)(-625 1300);
WIRE 16 -1 (-375 1350)(-375 1300);
WIRE 16 -1 (-375 1250)(-625 1250);
WIRE 16 -1 (-375 1300)(-375 1250);
WIRE 16 -1 (-375 1200)(-625 1200);
WIRE 16 -1 (-375 1250)(-375 1200);
WIRE 16 -1 (-625 1150)(-375 1150);
WIRE 16 -1 (-375 1150)(-375 1200);
WIRE 16 -1 (-375 1100)(-625 1100);
WIRE 16 -1 (-375 1100)(-375 1150);
WIRE 16 -1 (-375 1050)(-625 1050);
WIRE 16 -1 (-375 1100)(-375 1050);
WIRE 16 -1 (-375 1000)(-625 1000);
WIRE 16 -1 (-375 1050)(-375 1000);
WIRE 16 -1 (-625 950)(-375 950);
WIRE 16 -1 (-375 1000)(-375 950);
WIRE 16 -1 (-625 900)(-375 900);
WIRE 16 -1 (-375 950)(-375 900);
WIRE 16 -1 (-625 850)(-375 850);
WIRE 16 -1 (-375 900)(-375 850);
WIRE 16 -1 (-625 800)(-375 800);
WIRE 16 -1 (-375 850)(-375 800);
WIRE 16 -1 (-625 750)(-375 750);
WIRE 16 -1 (-375 800)(-375 750);
WIRE 16 -1 (-625 700)(-375 700);
WIRE 16 -1 (-375 750)(-375 700);
WIRE 16 -1 (-625 650)(-375 650);
WIRE 16 -1 (-375 700)(-375 650);
WIRE 16 -1 (-625 600)(-375 600);
WIRE 16 -1 (-375 600)(-375 650);
WIRE 16 -1 (-625 550)(-375 550);
WIRE 16 -1 (-375 600)(-375 550);
WIRE 16 -1 (-375 500)(-625 500);
WIRE 16 -1 (-375 550)(-375 500);
WIRE 16 -1 (-375 450)(-625 450);
WIRE 16 -1 (-375 500)(-375 450);
WIRE 16 -1 (-375 400)(-625 400);
WIRE 16 -1 (-375 450)(-375 400);
WIRE 16 -1 (-375 350)(-625 350);
WIRE 16 -1 (-375 400)(-375 350);
WIRE 16 -1 (-625 300)(-375 300);
WIRE 16 -1 (-375 300)(-375 350);
WIRE 16 -1 (-375 250)(-625 250);
WIRE 16 -1 (-375 250)(-375 300);
WIRE 16 -1 (-375 200)(-625 200);
WIRE 16 -1 (-375 250)(-375 200);
WIRE 16 -1 (-375 150)(-625 150);
WIRE 16 -1 (-375 200)(-375 150);
WIRE 16 -1 (-625 100)(-375 100);
WIRE 16 -1 (-375 150)(-375 100);
WIRE 16 -1 (-625 50)(-375 50);
WIRE 16 -1 (-375 100)(-375 50);
WIRE 16 -1 (-375 50)(-375 0);
WIRE 16 -1 (-625 0)(-375 0);
WIRE 16 -1 (-625 -50)(-375 -50);
WIRE 16 -1 (-375 0)(-375 -50);
WIRE 16 -1 (-625 -100)(-375 -100);
WIRE 16 -1 (-375 -50)(-375 -100);
WIRE 16 -1 (-625 -150)(-375 -150);
WIRE 16 -1 (-375 -100)(-375 -150);
WIRE 16 -1 (-625 -200)(-375 -200);
WIRE 16 -1 (-375 -150)(-375 -200);
WIRE 16 -1 (-375 -250)(-375 -200);
WIRE 16 -1 (-625 -250)(-375 -250);
DOT 1 (-375 3450);
DOT 1 (-225 3350);
DOT 1 (-375 3100);
DOT 1 (-3275 1400);
DOT 1 (-3275 -300);
DOT 1 (-3275 -250);
DOT 1 (-3275 -200);
DOT 1 (-3275 -150);
DOT 1 (-3275 0);
DOT 1 (-3275 -50);
DOT 1 (-3275 -100);
DOT 1 (-375 -300);
DOT 1 (-375 -250);
DOT 1 (-375 -150);
DOT 1 (-375 -100);
DOT 1 (-375 -50);
DOT 1 (-375 -200);
DOT 1 (-375 0);
DOT 1 (-225 -300);
DOT 1 (-225 -250);
DOT 1 (-225 -200);
DOT 1 (-225 -150);
DOT 1 (-225 -100);
DOT 1 (-225 0);
DOT 1 (-225 -50);
DOT 1 (-3275 50);
DOT 1 (-3275 100);
DOT 1 (-3275 150);
DOT 1 (-3275 200);
DOT 1 (-3275 250);
DOT 1 (-3275 350);
DOT 1 (-3275 300);
DOT 1 (-3275 400);
DOT 1 (-3275 450);
DOT 1 (-3275 500);
DOT 1 (-3275 550);
DOT 1 (-3275 600);
DOT 1 (-3275 650);
DOT 1 (-3275 700);
DOT 1 (-3275 750);
DOT 1 (-3275 850);
DOT 1 (-3275 800);
DOT 1 (-3275 900);
DOT 1 (-3275 950);
DOT 1 (-3275 1000);
DOT 1 (-3275 1050);
DOT 1 (-3275 1100);
DOT 1 (-3275 1150);
DOT 1 (-3275 1250);
DOT 1 (-3275 1200);
DOT 1 (-3275 1300);
DOT 1 (-3275 1350);
DOT 1 (-3275 1500);
DOT 1 (-3275 1450);
DOT 1 (-3275 1550);
DOT 1 (-3275 1600);
DOT 1 (-3275 1650);
DOT 1 (-3275 1750);
DOT 1 (-3275 1700);
DOT 1 (-3275 1800);
DOT 1 (-3275 1850);
DOT 1 (-3275 1900);
DOT 1 (-3275 2000);
DOT 1 (-3275 1950);
DOT 1 (-3275 2050);
DOT 1 (-3275 2100);
DOT 1 (-3275 2150);
DOT 1 (-3275 2200);
DOT 1 (-3275 2250);
DOT 1 (-3275 2300);
DOT 1 (-3275 2400);
DOT 1 (-3275 2350);
DOT 1 (-3275 2450);
DOT 1 (-3275 2500);
DOT 1 (-3275 2550);
DOT 1 (-3275 2600);
DOT 1 (-3275 2650);
DOT 1 (-3275 2700);
DOT 1 (-3275 2750);
DOT 1 (-3275 2800);
DOT 1 (-3275 2900);
DOT 1 (-3275 2850);
DOT 1 (-3275 2950);
DOT 1 (-3275 3000);
DOT 1 (-3275 3050);
DOT 1 (-3275 3200);
DOT 1 (-3275 3100);
DOT 1 (-3275 3150);
DOT 1 (-3275 3300);
DOT 1 (-3275 3350);
DOT 1 (-3275 3400);
DOT 1 (-3275 3450);
DOT 1 (-3275 3550);
DOT 1 (-3275 3500);
DOT 1 (-3275 3600);
DOT 1 (-375 100);
DOT 1 (-375 150);
DOT 1 (-375 200);
DOT 1 (-375 250);
DOT 1 (-375 50);
DOT 1 (-375 350);
DOT 1 (-375 400);
DOT 1 (-375 500);
DOT 1 (-375 450);
DOT 1 (-375 300);
DOT 1 (-225 50);
DOT 1 (-225 100);
DOT 1 (-225 150);
DOT 1 (-225 200);
DOT 1 (-225 250);
DOT 1 (-225 350);
DOT 1 (-225 300);
DOT 1 (-225 400);
DOT 1 (-225 450);
DOT 1 (-225 500);
DOT 1 (-375 600);
DOT 1 (-375 650);
DOT 1 (-375 700);
DOT 1 (-375 750);
DOT 1 (-375 550);
DOT 1 (-375 850);
DOT 1 (-375 900);
DOT 1 (-375 1000);
DOT 1 (-375 950);
DOT 1 (-375 800);
DOT 1 (-225 550);
DOT 1 (-225 600);
DOT 1 (-225 650);
DOT 1 (-225 700);
DOT 1 (-225 750);
DOT 1 (-225 850);
DOT 1 (-225 800);
DOT 1 (-225 900);
DOT 1 (-225 950);
DOT 1 (-225 1000);
DOT 1 (-375 1100);
DOT 1 (-375 1150);
DOT 1 (-375 1250);
DOT 1 (-375 1200);
DOT 1 (-375 1050);
DOT 1 (-375 1350);
DOT 1 (-375 1400);
DOT 1 (-375 1450);
DOT 1 (-375 1500);
DOT 1 (-375 1300);
DOT 1 (-225 1050);
DOT 1 (-225 1100);
DOT 1 (-225 1150);
DOT 1 (-225 1250);
DOT 1 (-225 1200);
DOT 1 (-225 1300);
DOT 1 (-225 1350);
DOT 1 (-225 1400);
DOT 1 (-225 1450);
DOT 1 (-225 1500);
DOT 1 (-375 1550);
DOT 1 (-375 1650);
DOT 1 (-375 1750);
DOT 1 (-375 1700);
DOT 1 (-375 1600);
DOT 1 (-375 1800);
DOT 1 (-375 1850);
DOT 1 (-375 1900);
DOT 1 (-375 1950);
DOT 1 (-375 2000);
DOT 1 (-225 1600);
DOT 1 (-225 1550);
DOT 1 (-225 1650);
DOT 1 (-225 1750);
DOT 1 (-225 1700);
DOT 1 (-225 1800);
DOT 1 (-225 1850);
DOT 1 (-225 1900);
DOT 1 (-225 1950);
DOT 1 (-225 2000);
DOT 1 (-225 2050);
DOT 1 (-375 2050);
DOT 1 (-375 2150);
DOT 1 (-375 2200);
DOT 1 (-375 2250);
DOT 1 (-375 2300);
DOT 1 (-375 2100);
DOT 1 (-375 2350);
DOT 1 (-375 2450);
DOT 1 (-375 2550);
DOT 1 (-375 2500);
DOT 1 (-375 2400);
DOT 1 (-225 2100);
DOT 1 (-225 2150);
DOT 1 (-225 2200);
DOT 1 (-225 2250);
DOT 1 (-225 2300);
DOT 1 (-225 2400);
DOT 1 (-225 2350);
DOT 1 (-225 2450);
DOT 1 (-225 2500);
DOT 1 (-225 2550);
DOT 1 (-375 2650);
DOT 1 (-375 2700);
DOT 1 (-375 2750);
DOT 1 (-375 2800);
DOT 1 (-375 2600);
DOT 1 (-375 2850);
DOT 1 (-375 2950);
DOT 1 (-375 3050);
DOT 1 (-375 3000);
DOT 1 (-375 2900);
DOT 1 (-225 2600);
DOT 1 (-225 2650);
DOT 1 (-225 2700);
DOT 1 (-225 2750);
DOT 1 (-225 2800);
DOT 1 (-225 2900);
DOT 1 (-225 2850);
DOT 1 (-225 2950);
DOT 1 (-225 3000);
DOT 1 (-225 3050);
DOT 1 (-375 3150);
DOT 1 (-375 3200);
DOT 1 (-375 3300);
DOT 1 (-375 3250);
DOT 1 (-375 3400);
DOT 1 (-375 3500);
DOT 1 (-375 3550);
DOT 1 (-375 3350);
DOT 1 (-225 3200);
DOT 1 (-225 3100);
DOT 1 (-225 3150);
DOT 1 (-225 3300);
DOT 1 (-225 3250);
DOT 1 (-225 3400);
DOT 1 (-225 3450);
DOT 1 (-225 3500);
DOT 1 (-225 3550);
DOT 1 (-375 3600);
DOT 1 (-225 3600);
DOT 1 (2675 -50);
DOT 1 (2675 -100);
DOT 1 (2675 0);
DOT 1 (2800 -200);
DOT 1 (2800 -150);
DOT 1 (2800 -100);
DOT 1 (2800 -50);
DOT 1 (2800 0);
DOT 1 (2675 100);
DOT 1 (2675 50);
DOT 1 (2675 150);
DOT 1 (2675 200);
DOT 1 (2675 250);
DOT 1 (2800 50);
DOT 1 (2800 100);
DOT 1 (2800 150);
DOT 1 (2800 200);
DOT 1 (2800 250);
DOT 1 (2675 300);
DOT 1 (2675 350);
DOT 1 (2675 400);
DOT 1 (2675 450);
DOT 1 (2675 500);
DOT 1 (2800 350);
DOT 1 (2800 300);
DOT 1 (2800 400);
DOT 1 (2800 450);
DOT 1 (2800 500);
DOT 1 (2675 600);
DOT 1 (2675 550);
DOT 1 (2675 650);
DOT 1 (2675 700);
DOT 1 (2675 750);
DOT 1 (2800 550);
DOT 1 (2800 600);
DOT 1 (2800 650);
DOT 1 (2800 700);
DOT 1 (2800 750);
DOT 1 (2675 800);
DOT 1 (2675 850);
DOT 1 (2675 900);
DOT 1 (2675 950);
DOT 1 (2675 1000);
DOT 1 (2800 850);
DOT 1 (2800 800);
DOT 1 (2800 900);
DOT 1 (2800 950);
DOT 1 (2800 1000);
DOT 1 (2675 1050);
DOT 1 (2675 1100);
DOT 1 (2675 1150);
DOT 1 (2675 1200);
DOT 1 (2675 1250);
DOT 1 (2800 1050);
DOT 1 (2800 1100);
DOT 1 (2800 1150);
DOT 1 (2800 1250);
DOT 1 (2800 1200);
DOT 1 (2675 1300);
DOT 1 (2675 1350);
DOT 1 (2675 1400);
DOT 1 (2675 1450);
DOT 1 (2675 1500);
DOT 1 (2800 1300);
DOT 1 (2800 1350);
DOT 1 (2800 1400);
DOT 1 (2800 1500);
DOT 1 (2800 1450);
DOT 1 (2675 1550);
DOT 1 (2675 1600);
DOT 1 (2675 1650);
DOT 1 (2675 1700);
DOT 1 (2675 1750);
DOT 1 (2800 1550);
DOT 1 (2800 1600);
DOT 1 (2800 1650);
DOT 1 (2800 1750);
DOT 1 (2800 1700);
DOT 1 (2800 1800);
DOT 1 (2675 1800);
DOT 1 (2675 1850);
DOT 1 (2675 1900);
DOT 1 (2675 1950);
DOT 1 (2675 2000);
DOT 1 (2800 1850);
DOT 1 (2800 1900);
DOT 1 (2800 2000);
DOT 1 (2800 1950);
DOT 1 (2800 2050);
DOT 1 (2675 2050);
DOT 1 (2675 2100);
DOT 1 (2675 2150);
DOT 1 (2675 2200);
DOT 1 (2675 2250);
DOT 1 (2675 2300);
DOT 1 (2800 2100);
DOT 1 (2800 2150);
DOT 1 (2800 2200);
DOT 1 (2800 2250);
DOT 1 (2800 2300);
DOT 1 (2675 2350);
DOT 1 (2675 2400);
DOT 1 (2675 2450);
DOT 1 (2675 2500);
DOT 1 (2675 2550);
DOT 1 (2800 2400);
DOT 1 (2800 2350);
DOT 1 (2800 2450);
DOT 1 (2800 2500);
DOT 1 (2800 2550);
DOT 1 (2675 2650);
DOT 1 (2675 2600);
DOT 1 (2675 2700);
DOT 1 (2675 2750);
DOT 1 (2675 2800);
DOT 1 (2800 2600);
DOT 1 (2800 2650);
DOT 1 (2800 2700);
DOT 1 (2800 2750);
DOT 1 (2800 2800);
DOT 1 (2675 2850);
DOT 1 (2675 2900);
DOT 1 (2675 2950);
DOT 1 (2675 3000);
DOT 1 (2675 3050);
DOT 1 (2800 2900);
DOT 1 (2800 2850);
DOT 1 (2800 2950);
DOT 1 (2800 3000);
DOT 1 (2800 3050);
DOT 1 (2675 3150);
DOT 1 (2675 3100);
DOT 1 (2675 3200);
DOT 1 (2675 3250);
DOT 1 (2675 3300);
DOT 1 (2800 3100);
DOT 1 (2800 3200);
DOT 1 (2800 3150);
DOT 1 (2800 3300);
DOT 1 (2800 3250);
DOT 1 (2675 3350);
DOT 1 (2675 3400);
DOT 1 (2675 3450);
DOT 1 (2675 3500);
DOT 1 (2675 3550);
DOT 1 (2800 3350);
DOT 1 (2800 3400);
DOT 1 (2800 3450);
DOT 1 (2800 3550);
DOT 1 (2800 3500);
DOT 1 (2675 3600);
DOT 1 (2800 3600);
DOT 1 (-3275 3250);
QUIT
